G04*
G04 #@! TF.GenerationSoftware,Altium Limited,Altium Designer,22.4.2 (48)*
G04*
G04 Layer_Physical_Order=4*
G04 Layer_Color=6736896*
%FSLAX25Y25*%
%MOIN*%
G70*
G04*
G04 #@! TF.SameCoordinates,446674BB-F454-490D-8607-5140536C8ADF*
G04*
G04*
G04 #@! TF.FilePolarity,Positive*
G04*
G01*
G75*
%ADD10C,0.01000*%
%ADD18C,0.00800*%
%ADD21C,0.00500*%
%ADD149C,0.02000*%
%ADD157C,0.05906*%
%ADD158R,0.05906X0.05906*%
%ADD159C,0.07500*%
%ADD167C,0.01600*%
%ADD168C,0.03200*%
G36*
X197835Y17717D02*
X305403D01*
X305523Y17217D01*
X304409Y16649D01*
X303033Y15650D01*
X301831Y14447D01*
X300832Y13072D01*
X300060Y11558D01*
X299535Y9941D01*
X299269Y8262D01*
Y6562D01*
X299535Y4883D01*
X300060Y3266D01*
X300832Y1751D01*
X301831Y376D01*
X303033Y-826D01*
X304409Y-1825D01*
X305923Y-2597D01*
X307540Y-3122D01*
X309219Y-3388D01*
X310919D01*
X312598Y-3122D01*
X314215Y-2597D01*
X315729Y-1825D01*
X317105Y-826D01*
X318307Y376D01*
X319306Y1751D01*
X320078Y3266D01*
X320603Y4883D01*
X320869Y6562D01*
Y8262D01*
X320603Y9941D01*
X320078Y11558D01*
X319306Y13072D01*
X318307Y14447D01*
X317105Y15650D01*
X315729Y16649D01*
X314615Y17217D01*
X314735Y17717D01*
X409084D01*
X409119Y17217D01*
X407696Y16491D01*
X406321Y15492D01*
X405119Y14290D01*
X404119Y12915D01*
X403347Y11400D01*
X402822Y9783D01*
X402556Y8104D01*
Y6404D01*
X402822Y4725D01*
X403347Y3109D01*
X404119Y1594D01*
X405119Y219D01*
X406321Y-983D01*
X407696Y-1983D01*
X409210Y-2754D01*
X410827Y-3280D01*
X412506Y-3546D01*
X414206D01*
X415885Y-3280D01*
X417502Y-2754D01*
X419017Y-1983D01*
X420392Y-983D01*
X421594Y219D01*
X422593Y1594D01*
X423365Y3109D01*
X423890Y4725D01*
X424156Y6404D01*
Y8104D01*
X423890Y9783D01*
X423365Y11400D01*
X422593Y12915D01*
X421594Y14290D01*
X420392Y15492D01*
X419017Y16491D01*
X417593Y17217D01*
X417629Y17717D01*
X547096D01*
X547230Y17217D01*
X546751Y16940D01*
X546052Y16241D01*
X545558Y15385D01*
X545302Y14431D01*
Y13443D01*
X545558Y12489D01*
X546052Y11633D01*
X546751Y10934D01*
X547607Y10440D01*
X548561Y10184D01*
X549549D01*
X550504Y10440D01*
X551359Y10934D01*
X552058Y11633D01*
X552552Y12489D01*
X552808Y13443D01*
Y14431D01*
X552552Y15385D01*
X552058Y16241D01*
X551359Y16940D01*
X550880Y17217D01*
X551014Y17717D01*
X557096D01*
X557230Y17217D01*
X556751Y16940D01*
X556052Y16241D01*
X555558Y15385D01*
X555302Y14431D01*
Y13443D01*
X555558Y12489D01*
X556052Y11633D01*
X556751Y10934D01*
X557607Y10440D01*
X558561Y10184D01*
X559549D01*
X560504Y10440D01*
X561359Y10934D01*
X562058Y11633D01*
X562552Y12489D01*
X562808Y13443D01*
Y14431D01*
X562552Y15385D01*
X562058Y16241D01*
X561359Y16940D01*
X560880Y17217D01*
X561014Y17717D01*
X567096D01*
X567230Y17217D01*
X566751Y16940D01*
X566052Y16241D01*
X565558Y15385D01*
X565302Y14431D01*
Y13443D01*
X565558Y12489D01*
X566052Y11633D01*
X566751Y10934D01*
X567607Y10440D01*
X568561Y10184D01*
X569549D01*
X570504Y10440D01*
X571359Y10934D01*
X572058Y11633D01*
X572552Y12489D01*
X572808Y13443D01*
Y14431D01*
X572552Y15385D01*
X572058Y16241D01*
X571359Y16940D01*
X570880Y17217D01*
X571014Y17717D01*
X577096D01*
X577230Y17217D01*
X576751Y16940D01*
X576052Y16241D01*
X575558Y15385D01*
X575302Y14431D01*
Y13443D01*
X575558Y12489D01*
X576052Y11633D01*
X576751Y10934D01*
X577607Y10440D01*
X578561Y10184D01*
X579549D01*
X580504Y10440D01*
X581359Y10934D01*
X582058Y11633D01*
X582552Y12489D01*
X582808Y13443D01*
Y14431D01*
X582552Y15385D01*
X582058Y16241D01*
X581359Y16940D01*
X580880Y17217D01*
X581014Y17717D01*
X584813D01*
X585302Y17690D01*
X585302Y17217D01*
Y10184D01*
X592808D01*
X592808Y17690D01*
X593297Y17717D01*
X647273D01*
X647308Y17217D01*
X645885Y16491D01*
X644510Y15492D01*
X643307Y14290D01*
X642308Y12915D01*
X641537Y11400D01*
X641011Y9783D01*
X640745Y8104D01*
Y6404D01*
X641011Y4725D01*
X641537Y3109D01*
X642308Y1594D01*
X643307Y219D01*
X644510Y-983D01*
X645885Y-1983D01*
X647400Y-2754D01*
X649016Y-3280D01*
X650695Y-3546D01*
X652395D01*
X654074Y-3280D01*
X655691Y-2754D01*
X657206Y-1983D01*
X658581Y-983D01*
X659783Y219D01*
X660782Y1594D01*
X661554Y3109D01*
X662079Y4725D01*
X662345Y6404D01*
Y8104D01*
X662079Y9783D01*
X661554Y11400D01*
X660782Y12915D01*
X659783Y14290D01*
X658581Y15492D01*
X657206Y16491D01*
X655783Y17217D01*
X655818Y17717D01*
X671260D01*
X671260Y-139764D01*
X633286D01*
X632750Y-139542D01*
X632113D01*
X631577Y-139764D01*
X549791Y-139764D01*
X535698Y-125671D01*
X535102Y-125273D01*
X534400Y-125133D01*
X533698Y-125273D01*
X533102Y-125671D01*
X532704Y-126266D01*
X532565Y-126969D01*
X532704Y-127671D01*
X533102Y-128266D01*
X544138Y-139302D01*
X543947Y-139764D01*
X470606D01*
X470356Y-139477D01*
X470427Y-138971D01*
X470877Y-138521D01*
X471121Y-137933D01*
Y-137296D01*
X470877Y-136708D01*
X470427Y-136258D01*
X469839Y-136015D01*
X469202D01*
X468614Y-136258D01*
X468164Y-136708D01*
X468120Y-136815D01*
X467630Y-136913D01*
X436889Y-106172D01*
X436492Y-105907D01*
X436024Y-105814D01*
X416975D01*
X416896Y-105314D01*
X417502Y-105117D01*
X419017Y-104345D01*
X420392Y-103346D01*
X421594Y-102144D01*
X422593Y-100768D01*
X423365Y-99254D01*
X423890Y-97637D01*
X424156Y-95958D01*
Y-94258D01*
X423890Y-92579D01*
X423365Y-90962D01*
X422593Y-89447D01*
X421594Y-88072D01*
X420392Y-86870D01*
X419017Y-85871D01*
X417502Y-85099D01*
X415885Y-84574D01*
X414206Y-84308D01*
X412506D01*
X410827Y-84574D01*
X409210Y-85099D01*
X407696Y-85871D01*
X406321Y-86870D01*
X405119Y-88072D01*
X404119Y-89447D01*
X403347Y-90962D01*
X402822Y-92579D01*
X402556Y-94258D01*
Y-95958D01*
X402822Y-97637D01*
X403347Y-99254D01*
X404119Y-100768D01*
X405119Y-102144D01*
X406321Y-103346D01*
X407696Y-104345D01*
X409210Y-105117D01*
X409817Y-105314D01*
X409737Y-105814D01*
X313204D01*
X313124Y-105314D01*
X314215Y-104959D01*
X315729Y-104187D01*
X317105Y-103188D01*
X318307Y-101986D01*
X319306Y-100611D01*
X320078Y-99096D01*
X320603Y-97479D01*
X320869Y-95800D01*
Y-94100D01*
X320603Y-92421D01*
X320078Y-90805D01*
X319306Y-89290D01*
X318307Y-87915D01*
X317105Y-86713D01*
X315729Y-85713D01*
X314215Y-84942D01*
X312598Y-84416D01*
X310919Y-84150D01*
X309219D01*
X307540Y-84416D01*
X305923Y-84942D01*
X304409Y-85713D01*
X303033Y-86713D01*
X301831Y-87915D01*
X300832Y-89290D01*
X300060Y-90805D01*
X299535Y-92421D01*
X299269Y-94100D01*
Y-95800D01*
X299535Y-97479D01*
X300060Y-99096D01*
X300832Y-100611D01*
X301831Y-101986D01*
X303033Y-103188D01*
X304409Y-104187D01*
X305923Y-104959D01*
X307014Y-105314D01*
X306934Y-105814D01*
X291353D01*
X269763Y-84223D01*
X269366Y-83958D01*
X268898Y-83865D01*
X116033D01*
X115756Y-83449D01*
X115773Y-83406D01*
Y-82770D01*
X115530Y-82182D01*
X115080Y-81732D01*
X114491Y-81488D01*
X113855D01*
X113267Y-81732D01*
X112817Y-82182D01*
X112573Y-82770D01*
Y-83406D01*
X112591Y-83449D01*
X112313Y-83865D01*
X89680D01*
X67168Y-61353D01*
Y-58962D01*
X67301Y-58829D01*
X67545Y-58241D01*
Y-57605D01*
X67301Y-57016D01*
X66851Y-56566D01*
X66263Y-56323D01*
X65627D01*
X65039Y-56566D01*
X64588Y-57016D01*
X64345Y-57605D01*
Y-58241D01*
X64588Y-58829D01*
X64721Y-58962D01*
Y-61860D01*
X64815Y-62328D01*
X65080Y-62725D01*
X66052Y-63697D01*
X65845Y-64197D01*
X65627D01*
X65039Y-64440D01*
X64588Y-64890D01*
X64345Y-65479D01*
Y-66115D01*
X64588Y-66703D01*
X65039Y-67153D01*
X65627Y-67397D01*
X65815D01*
X85946Y-87528D01*
X86343Y-87793D01*
X86811Y-87887D01*
X267505D01*
X289292Y-109674D01*
X289689Y-109939D01*
X290158Y-110032D01*
X369489D01*
X369657Y-110236D01*
Y-128347D01*
X369719Y-128659D01*
X369896Y-128923D01*
X369914Y-128936D01*
X369762Y-129436D01*
X310876D01*
X310598Y-129020D01*
X310616Y-128977D01*
Y-128341D01*
X310372Y-127753D01*
X309922Y-127303D01*
X309334Y-127059D01*
X308698D01*
X308109Y-127303D01*
X307659Y-127753D01*
X307416Y-128341D01*
Y-128977D01*
X307433Y-129020D01*
X307156Y-129436D01*
X275605D01*
X273700Y-127530D01*
X273700Y-127530D01*
X268923Y-122753D01*
Y-122565D01*
X268679Y-121977D01*
X268229Y-121527D01*
X267641Y-121283D01*
X267005D01*
X266417Y-121527D01*
X265966Y-121977D01*
X265723Y-122565D01*
Y-123202D01*
X265966Y-123790D01*
X266417Y-124240D01*
X267005Y-124484D01*
X267193D01*
X271970Y-129260D01*
X271970Y-129260D01*
X273065Y-130357D01*
X272874Y-130818D01*
X269138D01*
X268886Y-130567D01*
Y-130379D01*
X268643Y-129791D01*
X268193Y-129341D01*
X267605Y-129097D01*
X266968D01*
X266380Y-129341D01*
X265930Y-129791D01*
X265686Y-130379D01*
Y-131015D01*
X265930Y-131603D01*
X266114Y-131787D01*
X265907Y-132287D01*
X248538D01*
X244962Y-128711D01*
X244566Y-128446D01*
X244097Y-128353D01*
X238047D01*
X237914Y-128220D01*
X237326Y-127976D01*
X236690D01*
X236102Y-128220D01*
X235651Y-128670D01*
X235408Y-129258D01*
Y-129895D01*
X235651Y-130483D01*
X236102Y-130933D01*
X236690Y-131176D01*
X237326D01*
X237914Y-130933D01*
X238047Y-130800D01*
X243590D01*
X247166Y-134376D01*
X247563Y-134641D01*
X248031Y-134734D01*
X265449D01*
X265640Y-135196D01*
X265249Y-135588D01*
X235283D01*
X235171Y-135147D01*
X235169Y-135088D01*
X235608Y-134648D01*
X235626Y-134605D01*
X235667Y-134582D01*
X236200Y-134526D01*
X236495Y-134821D01*
X237083Y-135065D01*
X237720D01*
X238308Y-134821D01*
X238758Y-134371D01*
X238903Y-134022D01*
X239444D01*
X239588Y-134371D01*
X240038Y-134821D01*
X240627Y-135065D01*
X241263D01*
X241851Y-134821D01*
X242301Y-134371D01*
X242545Y-133783D01*
Y-133146D01*
X242301Y-132558D01*
X241851Y-132108D01*
X241263Y-131865D01*
X240627D01*
X240038Y-132108D01*
X239588Y-132558D01*
X239444Y-132907D01*
X238903D01*
X238758Y-132558D01*
X238308Y-132108D01*
X237720Y-131865D01*
X237083D01*
X236495Y-132108D01*
X236045Y-132558D01*
X236027Y-132601D01*
X235987Y-132624D01*
X235453Y-132680D01*
X235158Y-132385D01*
X234570Y-132142D01*
X233934D01*
X233346Y-132385D01*
X232896Y-132835D01*
X232652Y-133423D01*
Y-134060D01*
X232896Y-134648D01*
X233335Y-135088D01*
X233333Y-135147D01*
X233221Y-135588D01*
X90072D01*
X89604Y-135681D01*
X89385Y-135827D01*
X85183D01*
X85082Y-135726D01*
Y-130822D01*
X96570Y-119334D01*
X113386D01*
X113854Y-119241D01*
X114251Y-118975D01*
X115074Y-118153D01*
X115979D01*
X116029Y-118239D01*
X116132Y-118653D01*
X115770Y-119015D01*
X115526Y-119603D01*
Y-120239D01*
X115770Y-120828D01*
X116220Y-121278D01*
X116808Y-121521D01*
X117039D01*
X117465Y-121715D01*
X117494Y-121983D01*
Y-121985D01*
X117452Y-122372D01*
X117033Y-122447D01*
X116808D01*
X116220Y-122690D01*
X115770Y-123140D01*
X115526Y-123728D01*
Y-124365D01*
X115770Y-124953D01*
X116220Y-125403D01*
X116808Y-125647D01*
X117033D01*
X117452Y-125721D01*
X117488Y-126047D01*
X117452Y-126372D01*
X117033Y-126447D01*
X116808D01*
X116220Y-126690D01*
X115770Y-127140D01*
X115526Y-127728D01*
Y-128365D01*
X115770Y-128953D01*
X116220Y-129403D01*
X116808Y-129647D01*
X117033D01*
X117452Y-129721D01*
X117488Y-130047D01*
X117452Y-130372D01*
X117033Y-130447D01*
X116808D01*
X116220Y-130691D01*
X115770Y-131141D01*
X115526Y-131729D01*
Y-132366D01*
X115770Y-132954D01*
X116220Y-133404D01*
X116808Y-133647D01*
X117444D01*
X118032Y-133404D01*
X118482Y-132954D01*
X118726Y-132366D01*
Y-132109D01*
X118768Y-131721D01*
X119188Y-131647D01*
X119413D01*
X120001Y-131403D01*
X120451Y-130953D01*
X120694Y-130365D01*
Y-129728D01*
X120451Y-129140D01*
X120001Y-128690D01*
X119413Y-128447D01*
X119188D01*
X118768Y-128372D01*
X118733Y-128047D01*
X118768Y-127721D01*
X119188Y-127647D01*
X119413D01*
X120001Y-127403D01*
X120451Y-126953D01*
X120694Y-126365D01*
Y-125728D01*
X120451Y-125140D01*
X120001Y-124690D01*
X119413Y-124447D01*
X119188D01*
X118768Y-124372D01*
X118733Y-124047D01*
X118768Y-123721D01*
X119188Y-123647D01*
X119413D01*
X120001Y-123403D01*
X120451Y-122953D01*
X120694Y-122365D01*
Y-121728D01*
X120451Y-121140D01*
X120001Y-120690D01*
X119413Y-120447D01*
X119181D01*
X118755Y-120253D01*
X118726Y-119985D01*
Y-119603D01*
X118482Y-119015D01*
X118120Y-118653D01*
X118223Y-118239D01*
X118273Y-118153D01*
X138582D01*
X138898Y-118573D01*
X138865Y-118630D01*
X138609Y-119585D01*
Y-120573D01*
X138865Y-121527D01*
X139359Y-122383D01*
X140058Y-123082D01*
X140914Y-123576D01*
X141868Y-123831D01*
X142856D01*
X143811Y-123576D01*
X144666Y-123082D01*
X145365Y-122383D01*
X145859Y-121527D01*
X146115Y-120573D01*
Y-119585D01*
X145859Y-118630D01*
X145365Y-117774D01*
X144666Y-117076D01*
X143811Y-116582D01*
X142856Y-116326D01*
X141868D01*
X140914Y-116582D01*
X140712Y-116698D01*
X140078Y-116064D01*
X139828Y-115897D01*
X139979Y-115397D01*
X145950D01*
X148982Y-118429D01*
X148865Y-118630D01*
X148609Y-119585D01*
Y-120573D01*
X148865Y-121527D01*
X149359Y-122383D01*
X150058Y-123082D01*
X150914Y-123576D01*
X151868Y-123831D01*
X152856D01*
X153811Y-123576D01*
X154666Y-123082D01*
X155365Y-122383D01*
X155859Y-121527D01*
X156115Y-120573D01*
Y-119585D01*
X155859Y-118630D01*
X155365Y-117774D01*
X154666Y-117076D01*
X153811Y-116582D01*
X152856Y-116326D01*
X151868D01*
X150914Y-116582D01*
X150712Y-116698D01*
X147322Y-113308D01*
X146925Y-113043D01*
X146457Y-112950D01*
X114173D01*
X113705Y-113043D01*
X113308Y-113308D01*
X112288Y-114328D01*
X109748D01*
X109728Y-113836D01*
X110316Y-113593D01*
X110766Y-113143D01*
X111010Y-112555D01*
Y-111918D01*
X110766Y-111330D01*
X110316Y-110880D01*
X109728Y-110636D01*
X109408D01*
X109073Y-110577D01*
D01*
D01*
X108947Y-110174D01*
Y-109918D01*
X108703Y-109330D01*
X108253Y-108880D01*
X107665Y-108636D01*
X107028D01*
X106440Y-108880D01*
X105990Y-109330D01*
X105746Y-109918D01*
Y-110143D01*
X105672Y-110563D01*
X105347Y-110598D01*
D01*
X105080Y-110569D01*
X105021Y-110563D01*
X104946Y-110143D01*
Y-109918D01*
X104703Y-109330D01*
X104253Y-108880D01*
X103665Y-108636D01*
X103028D01*
X102440Y-108880D01*
X101990Y-109330D01*
X101746Y-109918D01*
Y-110143D01*
X101729Y-110198D01*
X101139Y-110408D01*
X100953Y-110298D01*
X100946Y-110143D01*
Y-109918D01*
X100703Y-109330D01*
X100253Y-108880D01*
X99665Y-108636D01*
X99028D01*
X98440Y-108880D01*
X97990Y-109330D01*
X97746Y-109918D01*
Y-110143D01*
X97613Y-110569D01*
X97285Y-110605D01*
X96965D01*
X96377Y-110848D01*
X95927Y-111298D01*
X95683Y-111887D01*
Y-112523D01*
X95927Y-113111D01*
X96377Y-113561D01*
X96965Y-113805D01*
X97602D01*
X98190Y-113561D01*
X98640Y-113111D01*
X98883Y-112523D01*
Y-112298D01*
X98901Y-112243D01*
X99491Y-112033D01*
X99677Y-112143D01*
X99683Y-112298D01*
Y-112523D01*
X99927Y-113111D01*
X100377Y-113561D01*
X100965Y-113805D01*
X101602D01*
X102190Y-113561D01*
X102640Y-113111D01*
X102884Y-112523D01*
Y-112298D01*
X103017Y-111872D01*
X103315Y-111839D01*
X103672Y-111878D01*
X103746Y-112298D01*
Y-112523D01*
X103990Y-113111D01*
X104440Y-113561D01*
X105028Y-113805D01*
X105665D01*
X106253Y-113561D01*
X106703Y-113111D01*
X106947Y-112523D01*
Y-112298D01*
X107021Y-111878D01*
X107371Y-111840D01*
X107683Y-111896D01*
X107772Y-112180D01*
X107809Y-112298D01*
Y-112555D01*
X108053Y-113143D01*
X108503Y-113593D01*
X109091Y-113836D01*
X109071Y-114328D01*
X94095D01*
X93626Y-114421D01*
X93229Y-114686D01*
X80631Y-127285D01*
X80366Y-127681D01*
X80273Y-128150D01*
Y-135827D01*
Y-142520D01*
X80366Y-142988D01*
X80631Y-143385D01*
X81028Y-143650D01*
X81496Y-143743D01*
X87317D01*
X87786Y-143650D01*
X88182Y-143385D01*
X89697Y-141870D01*
X89885D01*
X90473Y-141627D01*
X90923Y-141176D01*
X91167Y-140588D01*
Y-140400D01*
X92233Y-139334D01*
X95549D01*
X95827Y-139750D01*
X95810Y-139793D01*
Y-140429D01*
X96053Y-141017D01*
X96503Y-141467D01*
X97091Y-141711D01*
X97728D01*
X97809Y-141996D01*
Y-142051D01*
X98053Y-142639D01*
X98503Y-143089D01*
X99091Y-143332D01*
X99728D01*
X100316Y-143089D01*
X100766Y-142639D01*
X101010Y-142051D01*
X101248Y-141838D01*
X101794Y-141940D01*
X101810Y-141996D01*
Y-142051D01*
X102053Y-142639D01*
X102503Y-143089D01*
X103091Y-143332D01*
X103728D01*
X104316Y-143089D01*
X104766Y-142639D01*
X105009Y-142051D01*
X105248Y-141838D01*
X105793Y-141940D01*
X105809Y-141996D01*
Y-142051D01*
X106053Y-142639D01*
X106503Y-143089D01*
X107091Y-143332D01*
X107728D01*
X108316Y-143089D01*
X108766Y-142639D01*
X109009Y-142051D01*
Y-141996D01*
X109091Y-141711D01*
X109728D01*
X110316Y-141467D01*
X110766Y-141017D01*
X111009Y-140429D01*
Y-139793D01*
X110992Y-139750D01*
X111270Y-139334D01*
X122047D01*
Y-160271D01*
X89221D01*
X88753Y-160364D01*
X88356Y-160630D01*
X83697Y-165288D01*
X83432Y-165685D01*
X83339Y-166154D01*
Y-204385D01*
X82839Y-204592D01*
X82599Y-204352D01*
X82011Y-204109D01*
X81375D01*
X80787Y-204352D01*
X80336Y-204802D01*
X80093Y-205390D01*
Y-206027D01*
X80336Y-206615D01*
X80787Y-207065D01*
X81375Y-207309D01*
X82011D01*
X82599Y-207065D01*
X82839Y-206826D01*
X83339Y-207033D01*
Y-212714D01*
X83432Y-213182D01*
X83697Y-213579D01*
X84038Y-213920D01*
X84273Y-214489D01*
X84724Y-214939D01*
X85312Y-215183D01*
X85948D01*
X86536Y-214939D01*
X86986Y-214489D01*
X87230Y-213901D01*
Y-213264D01*
X87008Y-212730D01*
X87469Y-212539D01*
X87880Y-212127D01*
X88057Y-212146D01*
X88380Y-212281D01*
Y-220307D01*
X88304Y-220352D01*
X87880Y-220460D01*
X87520Y-220100D01*
X86932Y-219857D01*
X86296D01*
X85708Y-220100D01*
X85258Y-220550D01*
X85014Y-221138D01*
Y-221775D01*
X85258Y-222363D01*
X85708Y-222813D01*
X86296Y-223057D01*
X86932D01*
X87520Y-222813D01*
X87880Y-222453D01*
X88304Y-222561D01*
X88380Y-222606D01*
Y-257709D01*
X88304Y-257754D01*
X87880Y-257862D01*
X87520Y-257502D01*
X86932Y-257258D01*
X86296D01*
X85708Y-257502D01*
X85258Y-257952D01*
X85014Y-258540D01*
Y-259176D01*
X85258Y-259765D01*
X85708Y-260215D01*
X86296Y-260458D01*
X86514D01*
X86721Y-260958D01*
X85500Y-262179D01*
X85312D01*
X84724Y-262423D01*
X84273Y-262873D01*
X84030Y-263461D01*
Y-264098D01*
X84273Y-264686D01*
X84567Y-264980D01*
X84273Y-265273D01*
X84030Y-265861D01*
Y-266498D01*
X84273Y-267086D01*
X84724Y-267536D01*
X85312Y-267779D01*
X85948D01*
X86536Y-267536D01*
X86986Y-267086D01*
X87110Y-266787D01*
X87323Y-266645D01*
X90518Y-263450D01*
X90980Y-263641D01*
Y-310404D01*
X87692Y-313693D01*
X87168Y-313509D01*
X86986Y-313070D01*
X86536Y-312620D01*
X85948Y-312376D01*
X85312D01*
X84903Y-312546D01*
X84403Y-312287D01*
Y-303897D01*
X85511Y-302790D01*
X85776Y-302393D01*
X85869Y-301924D01*
Y-279050D01*
X87729Y-277190D01*
X87917D01*
X88505Y-276947D01*
X88955Y-276497D01*
X89198Y-275909D01*
Y-275272D01*
X88955Y-274684D01*
X88505Y-274234D01*
X87917Y-273991D01*
X87280D01*
X86692Y-274234D01*
X86242Y-274684D01*
X85998Y-275272D01*
Y-275460D01*
X83780Y-277678D01*
X83515Y-278075D01*
X83422Y-278543D01*
Y-286155D01*
X82922Y-286362D01*
X82786Y-286226D01*
X82198Y-285982D01*
X81561D01*
X80973Y-286226D01*
X80523Y-286676D01*
X80280Y-287264D01*
Y-287901D01*
X80523Y-288489D01*
X80656Y-288622D01*
Y-324990D01*
X80749Y-325458D01*
X81014Y-325855D01*
X82796Y-327637D01*
X83193Y-327902D01*
X83661Y-327995D01*
X86385D01*
X86565Y-328495D01*
X86242Y-328818D01*
X85998Y-329406D01*
Y-330043D01*
X86242Y-330631D01*
X86692Y-331081D01*
X87280Y-331324D01*
X87917D01*
X88505Y-331081D01*
X88536Y-331050D01*
X101378D01*
X101885Y-330949D01*
X102315Y-330662D01*
X116095Y-316882D01*
X116382Y-316452D01*
X116387Y-316429D01*
X116887Y-316478D01*
Y-318391D01*
X95950Y-339328D01*
X79779D01*
X79646Y-339195D01*
X79058Y-338951D01*
X78422D01*
X77834Y-339195D01*
X77384Y-339645D01*
X77140Y-340233D01*
Y-340869D01*
X77384Y-341458D01*
X77834Y-341908D01*
X78422Y-342151D01*
X79058D01*
X79646Y-341908D01*
X79779Y-341775D01*
X96457D01*
X96925Y-341682D01*
X97322Y-341416D01*
X118975Y-319763D01*
X119241Y-319366D01*
X119334Y-318898D01*
Y-264845D01*
X119834Y-264665D01*
X120157Y-264988D01*
X120745Y-265231D01*
X121381D01*
X121547Y-265163D01*
X122047Y-265497D01*
Y-360236D01*
X58268D01*
Y-135827D01*
X25591D01*
Y-10798D01*
X26006Y-10521D01*
X26177Y-10591D01*
X26814D01*
X27402Y-10348D01*
X27852Y-9898D01*
X28095Y-9310D01*
Y-8673D01*
X27852Y-8085D01*
X27402Y-7635D01*
X26814Y-7391D01*
X26177D01*
X26006Y-7462D01*
X25591Y-7184D01*
Y17865D01*
X67504D01*
X67624Y17365D01*
X66220Y16649D01*
X64844Y15650D01*
X63642Y14447D01*
X62643Y13072D01*
X61871Y11558D01*
X61346Y9941D01*
X61080Y8262D01*
Y6562D01*
X61346Y4883D01*
X61871Y3266D01*
X62643Y1751D01*
X63642Y376D01*
X64844Y-826D01*
X66220Y-1825D01*
X67734Y-2597D01*
X69351Y-3122D01*
X71030Y-3388D01*
X72730D01*
X74409Y-3122D01*
X76026Y-2597D01*
X77540Y-1825D01*
X78916Y-826D01*
X80118Y376D01*
X81117Y1751D01*
X81889Y3266D01*
X82414Y4883D01*
X82680Y6562D01*
Y8262D01*
X82414Y9941D01*
X81889Y11558D01*
X81117Y13072D01*
X80118Y14447D01*
X78916Y15650D01*
X77540Y16649D01*
X76135Y17365D01*
X76256Y17865D01*
X197835D01*
Y17717D01*
D02*
G37*
G36*
X398036Y-136467D02*
X398018Y-136509D01*
Y-136697D01*
X394952Y-139764D01*
X305993Y-139764D01*
X184245Y-139764D01*
X184055Y-139574D01*
Y-138034D01*
X265756D01*
X266224Y-137941D01*
X266621Y-137676D01*
X267585Y-136712D01*
X268085Y-136919D01*
Y-137161D01*
X268329Y-137749D01*
X268779Y-138199D01*
X269367Y-138443D01*
X270003D01*
X270591Y-138199D01*
X271041Y-137749D01*
X271285Y-137161D01*
Y-136524D01*
X271268Y-136482D01*
X271545Y-136066D01*
X395669D01*
X395744Y-136051D01*
X397758D01*
X398036Y-136467D01*
D02*
G37*
G36*
X464173Y-140460D02*
Y-144797D01*
X464010D01*
X463422Y-145041D01*
X462972Y-145491D01*
X462728Y-146079D01*
Y-146715D01*
X462972Y-147303D01*
X463422Y-147753D01*
X464010Y-147997D01*
X464173D01*
Y-181102D01*
X519291D01*
Y-209449D01*
X448819D01*
Y-174712D01*
X449319Y-174612D01*
X449493Y-175033D01*
X449943Y-175483D01*
X450531Y-175727D01*
X451168D01*
X451756Y-175483D01*
X452206Y-175033D01*
X452450Y-174445D01*
Y-173809D01*
X452206Y-173220D01*
X451756Y-172770D01*
X451168Y-172527D01*
X450531D01*
X449943Y-172770D01*
X449493Y-173220D01*
X449319Y-173641D01*
X448819Y-173542D01*
Y-164397D01*
X449190Y-164149D01*
X449826D01*
X450414Y-163905D01*
X450864Y-163455D01*
X451108Y-162867D01*
Y-162231D01*
X450864Y-161643D01*
X450414Y-161192D01*
X449826Y-160949D01*
X449190D01*
X448819Y-160701D01*
Y-159788D01*
X449319Y-159454D01*
X449485Y-159523D01*
X450121D01*
X450709Y-159279D01*
X451160Y-158829D01*
X451403Y-158241D01*
Y-157605D01*
X451160Y-157017D01*
X450709Y-156566D01*
X450121Y-156323D01*
X449485D01*
X449319Y-156392D01*
X448819Y-156058D01*
Y-146063D01*
X433768D01*
X423228Y-135523D01*
Y-128347D01*
X370472D01*
Y-110236D01*
X433949D01*
X464173Y-140460D01*
D02*
G37*
G36*
X88661Y-167727D02*
X89249Y-167970D01*
X89437D01*
X102826Y-181359D01*
X103223Y-181624D01*
X103691Y-181717D01*
X122047D01*
Y-185153D01*
X106597D01*
X106128Y-185246D01*
X105731Y-185511D01*
X86248Y-204995D01*
X85786Y-204804D01*
Y-171117D01*
X86202Y-170839D01*
X86244Y-170857D01*
X86880D01*
X87469Y-170613D01*
X87919Y-170163D01*
X88162Y-169575D01*
Y-168939D01*
X87919Y-168351D01*
X87846Y-168278D01*
X87943Y-167787D01*
X88074Y-167733D01*
X88371Y-167436D01*
X88661Y-167727D01*
D02*
G37*
G36*
X643701Y-253543D02*
X635039D01*
Y-243701D01*
X643701D01*
Y-253543D01*
D02*
G37*
G36*
X122047Y-198350D02*
X107513D01*
X107045Y-198443D01*
X106648Y-198708D01*
X96260Y-209096D01*
X95995Y-209493D01*
X95902Y-209961D01*
Y-218449D01*
X95769Y-218582D01*
X95525Y-219170D01*
Y-219806D01*
X95769Y-220394D01*
X96219Y-220845D01*
X96807Y-221088D01*
X97443D01*
X98032Y-220845D01*
X98482Y-220394D01*
X98725Y-219806D01*
Y-219170D01*
X98482Y-218582D01*
X98725Y-218118D01*
X98849Y-218035D01*
X99091Y-218135D01*
X99728D01*
X100316Y-217892D01*
X100766Y-217442D01*
X101010Y-216854D01*
Y-216629D01*
X101055Y-216212D01*
X101471Y-216167D01*
X101696D01*
X102284Y-215923D01*
X102734Y-215473D01*
X102978Y-214885D01*
Y-214249D01*
X102734Y-213661D01*
X102762Y-213542D01*
X102929Y-213148D01*
X103434Y-212939D01*
X103884Y-212489D01*
X104128Y-211901D01*
Y-211264D01*
X103931Y-210791D01*
X110026Y-204697D01*
X122047D01*
Y-209738D01*
X120732D01*
X120263Y-209831D01*
X119867Y-210096D01*
X110355Y-219607D01*
X110090Y-220004D01*
X109997Y-220472D01*
Y-310517D01*
X96934Y-323580D01*
X85153D01*
X84403Y-322830D01*
Y-322003D01*
X84903Y-321744D01*
X85312Y-321913D01*
X85948D01*
X86536Y-321670D01*
X86986Y-321220D01*
X87230Y-320632D01*
Y-320444D01*
X94369Y-313304D01*
X94634Y-312908D01*
X94727Y-312439D01*
Y-207330D01*
X108447Y-193611D01*
X122047D01*
Y-198350D01*
D02*
G37*
%LPC*%
G36*
X589549Y7690D02*
X588561D01*
X587607Y7434D01*
X586751Y6940D01*
X586052Y6241D01*
X585558Y5385D01*
X585302Y4431D01*
Y3443D01*
X585558Y2489D01*
X586052Y1633D01*
X586751Y934D01*
X587607Y440D01*
X588561Y184D01*
X589549D01*
X590504Y440D01*
X591359Y934D01*
X592058Y1633D01*
X592552Y2489D01*
X592808Y3443D01*
Y4431D01*
X592552Y5385D01*
X592058Y6241D01*
X591359Y6940D01*
X590504Y7434D01*
X589549Y7690D01*
D02*
G37*
G36*
X579549D02*
X578561D01*
X577607Y7434D01*
X576751Y6940D01*
X576052Y6241D01*
X575558Y5385D01*
X575302Y4431D01*
Y3443D01*
X575558Y2489D01*
X576052Y1633D01*
X576751Y934D01*
X577607Y440D01*
X578561Y184D01*
X579549D01*
X580504Y440D01*
X581359Y934D01*
X582058Y1633D01*
X582552Y2489D01*
X582808Y3443D01*
Y4431D01*
X582552Y5385D01*
X582058Y6241D01*
X581359Y6940D01*
X580504Y7434D01*
X579549Y7690D01*
D02*
G37*
G36*
X569549D02*
X568561D01*
X567607Y7434D01*
X566751Y6940D01*
X566052Y6241D01*
X565558Y5385D01*
X565302Y4431D01*
Y3443D01*
X565558Y2489D01*
X566052Y1633D01*
X566751Y934D01*
X567607Y440D01*
X568561Y184D01*
X569549D01*
X570504Y440D01*
X571359Y934D01*
X572058Y1633D01*
X572552Y2489D01*
X572808Y3443D01*
Y4431D01*
X572552Y5385D01*
X572058Y6241D01*
X571359Y6940D01*
X570504Y7434D01*
X569549Y7690D01*
D02*
G37*
G36*
X559549D02*
X558561D01*
X557607Y7434D01*
X556751Y6940D01*
X556052Y6241D01*
X555558Y5385D01*
X555302Y4431D01*
Y3443D01*
X555558Y2489D01*
X556052Y1633D01*
X556751Y934D01*
X557607Y440D01*
X558561Y184D01*
X559549D01*
X560504Y440D01*
X561359Y934D01*
X562058Y1633D01*
X562552Y2489D01*
X562808Y3443D01*
Y4431D01*
X562552Y5385D01*
X562058Y6241D01*
X561359Y6940D01*
X560504Y7434D01*
X559549Y7690D01*
D02*
G37*
G36*
X549549D02*
X548561D01*
X547607Y7434D01*
X546751Y6940D01*
X546052Y6241D01*
X545558Y5385D01*
X545302Y4431D01*
Y3443D01*
X545558Y2489D01*
X546052Y1633D01*
X546751Y934D01*
X547607Y440D01*
X548561Y184D01*
X549549D01*
X550504Y440D01*
X551359Y934D01*
X552058Y1633D01*
X552552Y2489D01*
X552808Y3443D01*
Y4431D01*
X552552Y5385D01*
X552058Y6241D01*
X551359Y6940D01*
X550504Y7434D01*
X549549Y7690D01*
D02*
G37*
G36*
X610555Y-7258D02*
X609918D01*
X609330Y-7502D01*
X608880Y-7952D01*
X608636Y-8540D01*
Y-9177D01*
X608880Y-9765D01*
X609330Y-10215D01*
X609918Y-10458D01*
X610555D01*
X611143Y-10215D01*
X611593Y-9765D01*
X611836Y-9177D01*
Y-8540D01*
X611593Y-7952D01*
X611143Y-7502D01*
X610555Y-7258D01*
D02*
G37*
G36*
X47562D02*
X46926D01*
X46338Y-7502D01*
X45888Y-7952D01*
X45644Y-8540D01*
Y-9177D01*
X45888Y-9765D01*
X46338Y-10215D01*
X46926Y-10458D01*
X47562D01*
X48150Y-10215D01*
X48601Y-9765D01*
X48844Y-9177D01*
Y-8540D01*
X48601Y-7952D01*
X48150Y-7502D01*
X47562Y-7258D01*
D02*
G37*
G36*
X40673D02*
X40036D01*
X39448Y-7502D01*
X38998Y-7952D01*
X38754Y-8540D01*
Y-9177D01*
X38998Y-9765D01*
X39448Y-10215D01*
X40036Y-10458D01*
X40673D01*
X41261Y-10215D01*
X41711Y-9765D01*
X41954Y-9177D01*
Y-8540D01*
X41711Y-7952D01*
X41261Y-7502D01*
X40673Y-7258D01*
D02*
G37*
G36*
X33783D02*
X33146D01*
X32558Y-7502D01*
X32108Y-7952D01*
X31865Y-8540D01*
Y-9177D01*
X32108Y-9765D01*
X32558Y-10215D01*
X33146Y-10458D01*
X33783D01*
X34371Y-10215D01*
X34821Y-9765D01*
X35065Y-9177D01*
Y-8540D01*
X34821Y-7952D01*
X34371Y-7502D01*
X33783Y-7258D01*
D02*
G37*
G36*
X641096Y-15666D02*
X640183D01*
X639339Y-16016D01*
X638693Y-16662D01*
X638344Y-17505D01*
Y-18419D01*
X638693Y-19263D01*
X639339Y-19909D01*
X640183Y-20258D01*
X641096D01*
X641940Y-19909D01*
X642586Y-19263D01*
X642936Y-18419D01*
Y-17505D01*
X642586Y-16662D01*
X641940Y-16016D01*
X641096Y-15666D01*
D02*
G37*
G36*
X658783Y-20299D02*
X658146D01*
X657558Y-20543D01*
X657108Y-20993D01*
X656865Y-21581D01*
Y-22218D01*
X657108Y-22806D01*
X657558Y-23256D01*
X658146Y-23499D01*
X658783D01*
X659371Y-23256D01*
X659821Y-22806D01*
X660065Y-22218D01*
Y-21581D01*
X659821Y-20993D01*
X659371Y-20543D01*
X658783Y-20299D01*
D02*
G37*
G36*
X625318D02*
X624682D01*
X624094Y-20543D01*
X623644Y-20993D01*
X623400Y-21581D01*
Y-22218D01*
X623644Y-22806D01*
X624094Y-23256D01*
X624682Y-23499D01*
X625318D01*
X625906Y-23256D01*
X626356Y-22806D01*
X626600Y-22218D01*
Y-21581D01*
X626356Y-20993D01*
X625906Y-20543D01*
X625318Y-20299D01*
D02*
G37*
G36*
X609570Y-24975D02*
X608934D01*
X608346Y-25218D01*
X607896Y-25668D01*
X607652Y-26256D01*
Y-26893D01*
X607896Y-27481D01*
X608346Y-27931D01*
X608934Y-28175D01*
X609570D01*
X610158Y-27931D01*
X610608Y-27481D01*
X610852Y-26893D01*
Y-26256D01*
X610608Y-25668D01*
X610158Y-25218D01*
X609570Y-24975D01*
D02*
G37*
G36*
X658783Y-28173D02*
X658146D01*
X657558Y-28417D01*
X657108Y-28867D01*
X656865Y-29455D01*
Y-30092D01*
X657108Y-30680D01*
X657558Y-31130D01*
X658146Y-31373D01*
X658783D01*
X659371Y-31130D01*
X659821Y-30680D01*
X660065Y-30092D01*
Y-29455D01*
X659821Y-28867D01*
X659371Y-28417D01*
X658783Y-28173D01*
D02*
G37*
G36*
X625318D02*
X624682D01*
X624094Y-28417D01*
X623644Y-28867D01*
X623400Y-29455D01*
Y-30092D01*
X623644Y-30680D01*
X623776Y-30812D01*
Y-35541D01*
X623361Y-35819D01*
X623318Y-35802D01*
X622682D01*
X622094Y-36045D01*
X621644Y-36495D01*
X621400Y-37083D01*
Y-37720D01*
X621644Y-38308D01*
X622094Y-38758D01*
X622682Y-39002D01*
X623318D01*
X623361Y-38984D01*
X623776Y-39262D01*
Y-47041D01*
X623644Y-47174D01*
X623400Y-47762D01*
Y-48399D01*
X623644Y-48987D01*
X624094Y-49437D01*
X624682Y-49680D01*
X625318D01*
X625906Y-49437D01*
X626356Y-48987D01*
X626600Y-48399D01*
Y-47762D01*
X626356Y-47174D01*
X626224Y-47041D01*
Y-30812D01*
X626356Y-30680D01*
X626600Y-30092D01*
Y-29455D01*
X626356Y-28867D01*
X625906Y-28417D01*
X625318Y-28173D01*
D02*
G37*
G36*
X641096Y-31414D02*
X640183D01*
X639339Y-31764D01*
X638693Y-32410D01*
X638344Y-33253D01*
Y-34167D01*
X638693Y-35011D01*
X639339Y-35657D01*
X640183Y-36006D01*
X641096D01*
X641940Y-35657D01*
X642586Y-35011D01*
X642936Y-34167D01*
Y-33253D01*
X642586Y-32410D01*
X641940Y-31764D01*
X641096Y-31414D01*
D02*
G37*
G36*
X658783Y-36047D02*
X658146D01*
X657558Y-36291D01*
X657108Y-36741D01*
X656865Y-37329D01*
Y-37966D01*
X657108Y-38554D01*
X657558Y-39004D01*
X658146Y-39247D01*
X658783D01*
X659371Y-39004D01*
X659821Y-38554D01*
X660065Y-37966D01*
Y-37329D01*
X659821Y-36741D01*
X659371Y-36291D01*
X658783Y-36047D01*
D02*
G37*
G36*
X645003Y-43676D02*
X644367D01*
X643779Y-43919D01*
X643329Y-44369D01*
X643085Y-44957D01*
Y-45594D01*
X643329Y-46182D01*
X643779Y-46632D01*
X644367Y-46876D01*
X645003D01*
X645591Y-46632D01*
X646041Y-46182D01*
X646285Y-45594D01*
Y-44957D01*
X646041Y-44369D01*
X645591Y-43919D01*
X645003Y-43676D01*
D02*
G37*
G36*
X99728Y-48449D02*
X99091D01*
X98503Y-48692D01*
X98053Y-49143D01*
X97809Y-49731D01*
Y-50367D01*
X98053Y-50955D01*
X98503Y-51405D01*
X99091Y-51649D01*
X99728D01*
X100316Y-51405D01*
X100766Y-50955D01*
X101010Y-50367D01*
Y-49731D01*
X100766Y-49143D01*
X100316Y-48692D01*
X99728Y-48449D01*
D02*
G37*
G36*
X66263D02*
X65627D01*
X65039Y-48692D01*
X64588Y-49143D01*
X64345Y-49731D01*
Y-50367D01*
X64588Y-50955D01*
X65039Y-51405D01*
X65627Y-51649D01*
X66263D01*
X66851Y-51405D01*
X67301Y-50955D01*
X67545Y-50367D01*
Y-49731D01*
X67301Y-49143D01*
X66851Y-48692D01*
X66263Y-48449D01*
D02*
G37*
G36*
X83242Y-51690D02*
X82329D01*
X81485Y-52039D01*
X80839Y-52685D01*
X80489Y-53529D01*
Y-54443D01*
X80839Y-55287D01*
X81485Y-55932D01*
X82329Y-56282D01*
X83242D01*
X84086Y-55932D01*
X84732Y-55287D01*
X85081Y-54443D01*
Y-53529D01*
X84732Y-52685D01*
X84086Y-52039D01*
X83242Y-51690D01*
D02*
G37*
G36*
X99728Y-56323D02*
X99091D01*
X98503Y-56566D01*
X98053Y-57016D01*
X97809Y-57605D01*
Y-58241D01*
X98053Y-58829D01*
X98503Y-59279D01*
X99091Y-59523D01*
X99728D01*
X100316Y-59279D01*
X100766Y-58829D01*
X101010Y-58241D01*
Y-57605D01*
X100766Y-57016D01*
X100316Y-56566D01*
X99728Y-56323D01*
D02*
G37*
G36*
X644019Y-62376D02*
X643383D01*
X642795Y-62620D01*
X642344Y-63070D01*
X642101Y-63658D01*
Y-64295D01*
X642344Y-64883D01*
X642795Y-65333D01*
X643383Y-65576D01*
X644019D01*
X644607Y-65333D01*
X645057Y-64883D01*
X645301Y-64295D01*
Y-63658D01*
X645057Y-63070D01*
X644607Y-62620D01*
X644019Y-62376D01*
D02*
G37*
G36*
X651875Y-62706D02*
X651238D01*
X650650Y-62950D01*
X650200Y-63400D01*
X649957Y-63988D01*
Y-64625D01*
X650200Y-65213D01*
X650650Y-65663D01*
X651238Y-65906D01*
X651875D01*
X652463Y-65663D01*
X652913Y-65213D01*
X653157Y-64625D01*
Y-63988D01*
X652913Y-63400D01*
X652463Y-62950D01*
X651875Y-62706D01*
D02*
G37*
G36*
X99728Y-64197D02*
X99091D01*
X98503Y-64440D01*
X98053Y-64890D01*
X97809Y-65479D01*
Y-66115D01*
X98053Y-66703D01*
X98503Y-67153D01*
X99091Y-67397D01*
X99728D01*
X100316Y-67153D01*
X100766Y-66703D01*
X101010Y-66115D01*
Y-65479D01*
X100766Y-64890D01*
X100316Y-64440D01*
X99728Y-64197D01*
D02*
G37*
G36*
X574334Y-68872D02*
X573698D01*
X573109Y-69116D01*
X572733Y-69492D01*
X572441Y-69534D01*
X572149Y-69492D01*
X571772Y-69116D01*
X571184Y-68872D01*
X570548D01*
X569960Y-69116D01*
X569510Y-69566D01*
X569266Y-70154D01*
Y-70791D01*
X569510Y-71379D01*
X569588Y-71457D01*
X569510Y-71535D01*
X569266Y-72123D01*
Y-72759D01*
X569510Y-73347D01*
X569588Y-73425D01*
X569510Y-73503D01*
X569266Y-74091D01*
Y-74728D01*
X569510Y-75316D01*
X569960Y-75766D01*
X570548Y-76010D01*
X571184D01*
X571772Y-75766D01*
X572149Y-75390D01*
X572441Y-75347D01*
X572733Y-75390D01*
X573109Y-75766D01*
X573698Y-76010D01*
X574334D01*
X574922Y-75766D01*
X575372Y-75316D01*
X575616Y-74728D01*
Y-74091D01*
X575372Y-73503D01*
X575294Y-73425D01*
X575372Y-73347D01*
X575616Y-72759D01*
Y-72123D01*
X575372Y-71535D01*
X575294Y-71457D01*
X575372Y-71379D01*
X575616Y-70791D01*
Y-70154D01*
X575372Y-69566D01*
X574922Y-69116D01*
X574334Y-68872D01*
D02*
G37*
G36*
X83242Y-67438D02*
X82329D01*
X81485Y-67787D01*
X80839Y-68433D01*
X80489Y-69277D01*
Y-70191D01*
X80839Y-71034D01*
X81485Y-71680D01*
X82329Y-72030D01*
X83242D01*
X84086Y-71680D01*
X84732Y-71034D01*
X85081Y-70191D01*
Y-69277D01*
X84732Y-68433D01*
X84086Y-67787D01*
X83242Y-67438D01*
D02*
G37*
G36*
X130239Y-77976D02*
X129603D01*
X129015Y-78220D01*
X128565Y-78670D01*
X128321Y-79258D01*
Y-79895D01*
X128565Y-80483D01*
X129015Y-80933D01*
X129603Y-81176D01*
X130239D01*
X130828Y-80933D01*
X131278Y-80483D01*
X131521Y-79895D01*
Y-79258D01*
X131278Y-78670D01*
X130828Y-78220D01*
X130239Y-77976D01*
D02*
G37*
G36*
X348645Y-86591D02*
X347777D01*
X346937Y-86816D01*
X346185Y-87250D01*
X345570Y-87865D01*
X345136Y-88617D01*
X344911Y-89456D01*
Y-90325D01*
X345136Y-91165D01*
X345570Y-91917D01*
X346185Y-92532D01*
X346937Y-92966D01*
X347777Y-93191D01*
X348645D01*
X349485Y-92966D01*
X350237Y-92532D01*
X350852Y-91917D01*
X351286Y-91165D01*
X351511Y-90325D01*
Y-89456D01*
X351286Y-88617D01*
X350852Y-87865D01*
X350237Y-87250D01*
X349485Y-86816D01*
X348645Y-86591D01*
D02*
G37*
G36*
X358232Y-86663D02*
X357364D01*
X356524Y-86888D01*
X355772Y-87323D01*
X355157Y-87937D01*
X354723Y-88690D01*
X354498Y-89529D01*
Y-90398D01*
X354723Y-91237D01*
X355157Y-91990D01*
X355772Y-92604D01*
X356524Y-93038D01*
X357364Y-93263D01*
X358232D01*
X359072Y-93038D01*
X359824Y-92604D01*
X360439Y-91990D01*
X360873Y-91237D01*
X361098Y-90398D01*
Y-89529D01*
X360873Y-88690D01*
X360439Y-87937D01*
X359824Y-87323D01*
X359072Y-86888D01*
X358232Y-86663D01*
D02*
G37*
G36*
X104846Y-90575D02*
X104209D01*
X103621Y-90818D01*
X103171Y-91268D01*
X102928Y-91857D01*
Y-92493D01*
X103171Y-93081D01*
X103621Y-93531D01*
X104209Y-93775D01*
X104846D01*
X105434Y-93531D01*
X105884Y-93081D01*
X106128Y-92493D01*
Y-91857D01*
X105884Y-91268D01*
X105434Y-90818D01*
X104846Y-90575D01*
D02*
G37*
G36*
X98743Y-100762D02*
X98107D01*
X97519Y-101006D01*
X97069Y-101456D01*
X96825Y-102044D01*
Y-102681D01*
X97069Y-103269D01*
X97519Y-103719D01*
X98107Y-103962D01*
X98743D01*
X99331Y-103719D01*
X99782Y-103269D01*
X100025Y-102681D01*
Y-102044D01*
X99782Y-101456D01*
X99331Y-101006D01*
X98743Y-100762D01*
D02*
G37*
G36*
X89885D02*
X89249D01*
X88661Y-101006D01*
X88210Y-101456D01*
X87967Y-102044D01*
Y-102681D01*
X88210Y-103269D01*
X88661Y-103719D01*
X89249Y-103962D01*
X89885D01*
X90473Y-103719D01*
X90923Y-103269D01*
X91167Y-102681D01*
Y-102044D01*
X90923Y-101456D01*
X90473Y-101006D01*
X89885Y-100762D01*
D02*
G37*
G36*
X72730Y-84150D02*
X71030D01*
X69351Y-84416D01*
X67734Y-84942D01*
X66220Y-85713D01*
X64844Y-86713D01*
X63642Y-87915D01*
X62643Y-89290D01*
X61871Y-90805D01*
X61346Y-92421D01*
X61080Y-94100D01*
Y-95800D01*
X61346Y-97479D01*
X61871Y-99096D01*
X62643Y-100611D01*
X63642Y-101986D01*
X64844Y-103188D01*
X66220Y-104187D01*
X67734Y-104959D01*
X69351Y-105484D01*
X71030Y-105751D01*
X72730D01*
X74409Y-105484D01*
X76026Y-104959D01*
X77540Y-104187D01*
X78916Y-103188D01*
X80118Y-101986D01*
X81117Y-100611D01*
X81889Y-99096D01*
X82414Y-97479D01*
X82680Y-95800D01*
Y-94100D01*
X82414Y-92421D01*
X81889Y-90805D01*
X81117Y-89290D01*
X80118Y-87915D01*
X78916Y-86713D01*
X77540Y-85713D01*
X76026Y-84942D01*
X74409Y-84416D01*
X72730Y-84150D01*
D02*
G37*
G36*
X528862Y-102614D02*
X528225D01*
X527637Y-102858D01*
X527187Y-103308D01*
X526943Y-103896D01*
Y-104532D01*
X527187Y-105121D01*
X527637Y-105571D01*
X528225Y-105814D01*
X528862D01*
X529450Y-105571D01*
X529900Y-105121D01*
X530143Y-104532D01*
Y-103896D01*
X529900Y-103308D01*
X529450Y-102858D01*
X528862Y-102614D01*
D02*
G37*
G36*
X519019D02*
X518383D01*
X517794Y-102858D01*
X517344Y-103308D01*
X517101Y-103896D01*
Y-104532D01*
X517344Y-105121D01*
X517794Y-105571D01*
X518383Y-105814D01*
X519019D01*
X519607Y-105571D01*
X520057Y-105121D01*
X520301Y-104532D01*
Y-103896D01*
X520057Y-103308D01*
X519607Y-102858D01*
X519019Y-102614D01*
D02*
G37*
G36*
X652395Y-84308D02*
X650695D01*
X649016Y-84574D01*
X647400Y-85099D01*
X645885Y-85871D01*
X644510Y-86870D01*
X643307Y-88072D01*
X642308Y-89447D01*
X641537Y-90962D01*
X641011Y-92579D01*
X640745Y-94258D01*
Y-95958D01*
X641011Y-97637D01*
X641537Y-99254D01*
X642308Y-100768D01*
X643307Y-102144D01*
X644510Y-103346D01*
X645885Y-104345D01*
X647400Y-105117D01*
X649016Y-105642D01*
X650695Y-105908D01*
X652395D01*
X654074Y-105642D01*
X655691Y-105117D01*
X657206Y-104345D01*
X658581Y-103346D01*
X659783Y-102144D01*
X660782Y-100768D01*
X661554Y-99254D01*
X662079Y-97637D01*
X662345Y-95958D01*
Y-94258D01*
X662079Y-92579D01*
X661554Y-90962D01*
X660782Y-89447D01*
X659783Y-88072D01*
X658581Y-86870D01*
X657206Y-85871D01*
X655691Y-85099D01*
X654074Y-84574D01*
X652395Y-84308D01*
D02*
G37*
G36*
X571046Y-104062D02*
X570409D01*
X569821Y-104306D01*
X569371Y-104756D01*
X569128Y-105344D01*
Y-105981D01*
X569371Y-106569D01*
X569821Y-107019D01*
X570409Y-107262D01*
X571046D01*
X571634Y-107019D01*
X572084Y-106569D01*
X572328Y-105981D01*
Y-105344D01*
X572084Y-104756D01*
X571634Y-104306D01*
X571046Y-104062D01*
D02*
G37*
G36*
X264098Y-104551D02*
X263461D01*
X262873Y-104795D01*
X262423Y-105245D01*
X262179Y-105833D01*
Y-106469D01*
X262423Y-107057D01*
X262873Y-107508D01*
X263461Y-107751D01*
X264098D01*
X264686Y-107508D01*
X265136Y-107057D01*
X265380Y-106469D01*
Y-105833D01*
X265136Y-105245D01*
X264686Y-104795D01*
X264098Y-104551D01*
D02*
G37*
G36*
X545132Y-108205D02*
X544495D01*
X543907Y-108449D01*
X543457Y-108899D01*
X543213Y-109487D01*
Y-110124D01*
X543457Y-110712D01*
X543907Y-111162D01*
X544495Y-111406D01*
X545132D01*
X545720Y-111162D01*
X546170Y-110712D01*
X546413Y-110124D01*
Y-109487D01*
X546170Y-108899D01*
X545720Y-108449D01*
X545132Y-108205D01*
D02*
G37*
G36*
X86932Y-108636D02*
X86296D01*
X85708Y-108880D01*
X85258Y-109330D01*
X85014Y-109918D01*
Y-110555D01*
X85258Y-111143D01*
X85708Y-111593D01*
X86296Y-111836D01*
X86932D01*
X87520Y-111593D01*
X87971Y-111143D01*
X88214Y-110555D01*
Y-109918D01*
X87971Y-109330D01*
X87520Y-108880D01*
X86932Y-108636D01*
D02*
G37*
G36*
X355043Y-112180D02*
X354406D01*
X353818Y-112423D01*
X353740Y-112501D01*
X353662Y-112423D01*
X353074Y-112180D01*
X352438D01*
X351850Y-112423D01*
X351772Y-112501D01*
X351694Y-112423D01*
X351106Y-112180D01*
X350469D01*
X349881Y-112423D01*
X349431Y-112873D01*
X349187Y-113461D01*
Y-114098D01*
X349431Y-114686D01*
X349807Y-115062D01*
X349850Y-115354D01*
X349807Y-115647D01*
X349431Y-116023D01*
X349187Y-116611D01*
Y-117247D01*
X349431Y-117835D01*
X349881Y-118286D01*
X350469Y-118529D01*
X351106D01*
X351694Y-118286D01*
X351772Y-118208D01*
X351850Y-118286D01*
X352438Y-118529D01*
X353074D01*
X353662Y-118286D01*
X353740Y-118208D01*
X353818Y-118286D01*
X354406Y-118529D01*
X355043D01*
X355631Y-118286D01*
X356081Y-117835D01*
X356324Y-117247D01*
Y-116611D01*
X356081Y-116023D01*
X355705Y-115647D01*
X355662Y-115354D01*
X355705Y-115062D01*
X356081Y-114686D01*
X356324Y-114098D01*
Y-113461D01*
X356081Y-112873D01*
X355631Y-112423D01*
X355043Y-112180D01*
D02*
G37*
G36*
X309334Y-112386D02*
X308698D01*
X308109Y-112629D01*
X307659Y-113080D01*
X307416Y-113668D01*
Y-114304D01*
X307659Y-114892D01*
X308109Y-115342D01*
X308698Y-115586D01*
X309334D01*
X309922Y-115342D01*
X310372Y-114892D01*
X310616Y-114304D01*
Y-113668D01*
X310372Y-113080D01*
X309922Y-112629D01*
X309334Y-112386D01*
D02*
G37*
G36*
X194216Y-113409D02*
X193579D01*
X192991Y-113653D01*
X192541Y-114103D01*
X192298Y-114691D01*
Y-115328D01*
X192541Y-115916D01*
X192991Y-116366D01*
X193579Y-116609D01*
X194216D01*
X194804Y-116366D01*
X195254Y-115916D01*
X195498Y-115328D01*
Y-114691D01*
X195254Y-114103D01*
X194804Y-113653D01*
X194216Y-113409D01*
D02*
G37*
G36*
X483586Y-112425D02*
X482949D01*
X482361Y-112669D01*
X482229Y-112802D01*
X458760D01*
X458292Y-112895D01*
X457895Y-113160D01*
X456612Y-114443D01*
X456424D01*
X455836Y-114687D01*
X455386Y-115137D01*
X455142Y-115725D01*
Y-116361D01*
X455386Y-116949D01*
X455836Y-117399D01*
X456424Y-117643D01*
X457060D01*
X457649Y-117399D01*
X458099Y-116949D01*
X458342Y-116361D01*
Y-116173D01*
X459267Y-115249D01*
X461691D01*
X461969Y-115664D01*
X461951Y-115707D01*
Y-116343D01*
X462195Y-116931D01*
X462645Y-117382D01*
X463233Y-117625D01*
X463869D01*
X464458Y-117382D01*
X464590Y-117249D01*
X485236D01*
X485704Y-117156D01*
X486101Y-116890D01*
X487335Y-115657D01*
X487523D01*
X488111Y-115413D01*
X488561Y-114963D01*
X488805Y-114375D01*
Y-113738D01*
X488561Y-113150D01*
X488111Y-112700D01*
X487523Y-112457D01*
X486887D01*
X486298Y-112700D01*
X485848Y-113150D01*
X485605Y-113738D01*
Y-113747D01*
X485368Y-113929D01*
X484868Y-113707D01*
X484624Y-113119D01*
X484174Y-112669D01*
X483586Y-112425D01*
D02*
G37*
G36*
X614640Y-116707D02*
X614003D01*
X613415Y-116951D01*
X612965Y-117401D01*
X612721Y-117989D01*
Y-118625D01*
X612965Y-119213D01*
X613415Y-119664D01*
X614003Y-119907D01*
X614640D01*
X615228Y-119664D01*
X615678Y-119213D01*
X615921Y-118625D01*
Y-117989D01*
X615678Y-117401D01*
X615228Y-116951D01*
X614640Y-116707D01*
D02*
G37*
G36*
X315279Y-117347D02*
X314642D01*
X314054Y-117590D01*
X313604Y-118040D01*
X313361Y-118628D01*
Y-119265D01*
X313604Y-119853D01*
X314054Y-120303D01*
X314642Y-120546D01*
X315279D01*
X315867Y-120303D01*
X316317Y-119853D01*
X316561Y-119265D01*
Y-118628D01*
X316317Y-118040D01*
X315867Y-117590D01*
X315279Y-117347D01*
D02*
G37*
G36*
X194216Y-118331D02*
X193579D01*
X192991Y-118574D01*
X192541Y-119024D01*
X192298Y-119612D01*
Y-120249D01*
X192541Y-120837D01*
X192991Y-121287D01*
X193579Y-121531D01*
X194216D01*
X194804Y-121287D01*
X195254Y-120837D01*
X195498Y-120249D01*
Y-119612D01*
X195254Y-119024D01*
X194804Y-118574D01*
X194216Y-118331D01*
D02*
G37*
G36*
X250318Y-119315D02*
X249682D01*
X249094Y-119559D01*
X248644Y-120009D01*
X248400Y-120597D01*
Y-121233D01*
X248644Y-121821D01*
X249094Y-122271D01*
X249682Y-122515D01*
X250318D01*
X250906Y-122271D01*
X251356Y-121821D01*
X251600Y-121233D01*
Y-120597D01*
X251356Y-120009D01*
X250906Y-119559D01*
X250318Y-119315D01*
D02*
G37*
G36*
X108032Y-119869D02*
X107322D01*
X106667Y-120141D01*
X106165Y-120643D01*
X105893Y-121299D01*
Y-122008D01*
X106165Y-122664D01*
X106667Y-123166D01*
X107322Y-123438D01*
X108032D01*
X108688Y-123166D01*
X109190Y-122664D01*
X109461Y-122008D01*
Y-121299D01*
X109190Y-120643D01*
X108688Y-120141D01*
X108032Y-119869D01*
D02*
G37*
G36*
X103701D02*
X102992D01*
X102336Y-120141D01*
X101834Y-120643D01*
X101562Y-121299D01*
Y-122008D01*
X101834Y-122664D01*
X102336Y-123166D01*
X102992Y-123438D01*
X103701D01*
X104357Y-123166D01*
X104859Y-122664D01*
X105131Y-122008D01*
Y-121299D01*
X104859Y-120643D01*
X104357Y-120141D01*
X103701Y-119869D01*
D02*
G37*
G36*
X99371D02*
X98661D01*
X98005Y-120141D01*
X97503Y-120643D01*
X97232Y-121299D01*
Y-122008D01*
X97503Y-122664D01*
X98005Y-123166D01*
X98661Y-123438D01*
X99371D01*
X100026Y-123166D01*
X100528Y-122664D01*
X100800Y-122008D01*
Y-121299D01*
X100528Y-120643D01*
X100026Y-120141D01*
X99371Y-119869D01*
D02*
G37*
G36*
X162856Y-116326D02*
X161868D01*
X160914Y-116582D01*
X160058Y-117076D01*
X159359Y-117774D01*
X158865Y-118630D01*
X158609Y-119585D01*
Y-120573D01*
X158865Y-121527D01*
X159359Y-122383D01*
X160058Y-123082D01*
X160914Y-123576D01*
X161868Y-123831D01*
X162856D01*
X163811Y-123576D01*
X164666Y-123082D01*
X165365Y-122383D01*
X165859Y-121527D01*
X166115Y-120573D01*
Y-119585D01*
X165859Y-118630D01*
X165365Y-117774D01*
X164666Y-117076D01*
X163811Y-116582D01*
X162856Y-116326D01*
D02*
G37*
G36*
X309373Y-122268D02*
X308737D01*
X308149Y-122511D01*
X307699Y-122961D01*
X307455Y-123549D01*
Y-124186D01*
X307699Y-124774D01*
X308149Y-125224D01*
X308737Y-125468D01*
X309373D01*
X309962Y-125224D01*
X310412Y-124774D01*
X310655Y-124186D01*
Y-123549D01*
X310412Y-122961D01*
X309962Y-122511D01*
X309373Y-122268D01*
D02*
G37*
G36*
X257208Y-120299D02*
X256572D01*
X255983Y-120543D01*
X255533Y-120993D01*
X255290Y-121581D01*
Y-122218D01*
X255533Y-122806D01*
X255777Y-123049D01*
X255928Y-123376D01*
X255777Y-123702D01*
X255533Y-123946D01*
X255290Y-124534D01*
Y-125170D01*
X255533Y-125758D01*
X255983Y-126208D01*
X256572Y-126452D01*
X257208D01*
X257796Y-126208D01*
X258246Y-125758D01*
X258490Y-125170D01*
Y-124534D01*
X258246Y-123946D01*
X258003Y-123702D01*
X257852Y-123376D01*
X258003Y-123049D01*
X258246Y-122806D01*
X258490Y-122218D01*
Y-121581D01*
X258246Y-120993D01*
X257796Y-120543D01*
X257208Y-120299D01*
D02*
G37*
G36*
X473743D02*
X473107D01*
X472519Y-120543D01*
X472069Y-120993D01*
X471825Y-121581D01*
Y-122218D01*
X472069Y-122806D01*
X472147Y-122883D01*
X472069Y-122961D01*
X471825Y-123549D01*
Y-124186D01*
X472069Y-124774D01*
X472147Y-124852D01*
X472069Y-124930D01*
X471825Y-125518D01*
Y-126154D01*
X472069Y-126743D01*
X472519Y-127193D01*
X473107Y-127436D01*
X473743D01*
X474332Y-127193D01*
X474782Y-126743D01*
X475025Y-126154D01*
Y-125518D01*
X474782Y-124930D01*
X474704Y-124852D01*
X474782Y-124774D01*
X475025Y-124186D01*
Y-123549D01*
X474782Y-122961D01*
X474704Y-122883D01*
X474782Y-122806D01*
X475025Y-122218D01*
Y-121581D01*
X474782Y-120993D01*
X474332Y-120543D01*
X473743Y-120299D01*
D02*
G37*
G36*
X108032Y-124200D02*
X107322D01*
X106667Y-124472D01*
X106165Y-124974D01*
X105893Y-125629D01*
Y-126339D01*
X106165Y-126995D01*
X106667Y-127497D01*
X107322Y-127769D01*
X108032D01*
X108688Y-127497D01*
X109190Y-126995D01*
X109461Y-126339D01*
Y-125629D01*
X109190Y-124974D01*
X108688Y-124472D01*
X108032Y-124200D01*
D02*
G37*
G36*
X103701D02*
X102992D01*
X102336Y-124472D01*
X101834Y-124974D01*
X101562Y-125629D01*
Y-126339D01*
X101834Y-126995D01*
X102336Y-127497D01*
X102992Y-127769D01*
X103701D01*
X104357Y-127497D01*
X104859Y-126995D01*
X105131Y-126339D01*
Y-125629D01*
X104859Y-124974D01*
X104357Y-124472D01*
X103701Y-124200D01*
D02*
G37*
G36*
X99371D02*
X98661D01*
X98005Y-124472D01*
X97503Y-124974D01*
X97232Y-125629D01*
Y-126339D01*
X97503Y-126995D01*
X98005Y-127497D01*
X98661Y-127769D01*
X99371D01*
X100026Y-127497D01*
X100528Y-126995D01*
X100800Y-126339D01*
Y-125629D01*
X100528Y-124974D01*
X100026Y-124472D01*
X99371Y-124200D01*
D02*
G37*
G36*
X331027Y-118872D02*
X330390D01*
X329802Y-119116D01*
X329352Y-119566D01*
X329109Y-120154D01*
Y-120791D01*
X329352Y-121379D01*
X329596Y-121622D01*
X329747Y-121949D01*
X329596Y-122275D01*
X329352Y-122519D01*
X329109Y-123107D01*
Y-123743D01*
X329352Y-124331D01*
X329596Y-124575D01*
X329747Y-124902D01*
X329596Y-125228D01*
X329352Y-125472D01*
X329109Y-126060D01*
Y-126696D01*
X329352Y-127284D01*
X329802Y-127734D01*
X330390Y-127978D01*
X331027D01*
X331615Y-127734D01*
X332065Y-127284D01*
X332309Y-126696D01*
Y-126060D01*
X332065Y-125472D01*
X331822Y-125228D01*
X331670Y-124902D01*
X331822Y-124575D01*
X332065Y-124331D01*
X332309Y-123743D01*
Y-123107D01*
X332065Y-122519D01*
X331822Y-122275D01*
X331670Y-121949D01*
X331822Y-121622D01*
X332065Y-121379D01*
X332309Y-120791D01*
Y-120154D01*
X332065Y-119566D01*
X331615Y-119116D01*
X331027Y-118872D01*
D02*
G37*
G36*
X524925Y-124236D02*
X524288D01*
X523700Y-124480D01*
X523250Y-124930D01*
X523006Y-125518D01*
Y-126154D01*
X523250Y-126743D01*
X523444Y-126937D01*
X523620Y-127317D01*
X523444Y-127590D01*
X523201Y-127833D01*
X522957Y-128421D01*
Y-129058D01*
X523201Y-129646D01*
X523651Y-130096D01*
X524239Y-130340D01*
X524875D01*
X525463Y-130096D01*
X525913Y-129646D01*
X526157Y-129058D01*
Y-128421D01*
X525913Y-127833D01*
X525719Y-127639D01*
X525543Y-127259D01*
X525719Y-126986D01*
X525963Y-126743D01*
X526206Y-126154D01*
Y-125518D01*
X525963Y-124930D01*
X525513Y-124480D01*
X524925Y-124236D01*
D02*
G37*
G36*
X108032Y-128531D02*
X107322D01*
X106667Y-128802D01*
X106165Y-129304D01*
X105893Y-129960D01*
Y-130670D01*
X106165Y-131326D01*
X106667Y-131828D01*
X107322Y-132099D01*
X108032D01*
X108688Y-131828D01*
X109190Y-131326D01*
X109461Y-130670D01*
Y-129960D01*
X109190Y-129304D01*
X108688Y-128802D01*
X108032Y-128531D01*
D02*
G37*
G36*
X103701D02*
X102992D01*
X102336Y-128802D01*
X101834Y-129304D01*
X101562Y-129960D01*
Y-130670D01*
X101834Y-131326D01*
X102336Y-131828D01*
X102992Y-132099D01*
X103701D01*
X104357Y-131828D01*
X104859Y-131326D01*
X105131Y-130670D01*
Y-129960D01*
X104859Y-129304D01*
X104357Y-128802D01*
X103701Y-128531D01*
D02*
G37*
G36*
X99371D02*
X98661D01*
X98005Y-128802D01*
X97503Y-129304D01*
X97232Y-129960D01*
Y-130670D01*
X97503Y-131326D01*
X98005Y-131828D01*
X98661Y-132099D01*
X99371D01*
X100026Y-131828D01*
X100528Y-131326D01*
X100800Y-130670D01*
Y-129960D01*
X100528Y-129304D01*
X100026Y-128802D01*
X99371Y-128531D01*
D02*
G37*
G36*
X76106Y-130290D02*
X75469D01*
X74881Y-130533D01*
X74431Y-130983D01*
X74187Y-131571D01*
Y-132208D01*
X74431Y-132796D01*
X74881Y-133246D01*
X75469Y-133490D01*
X76106D01*
X76694Y-133246D01*
X77144Y-132796D01*
X77387Y-132208D01*
Y-131571D01*
X77144Y-130983D01*
X76694Y-130533D01*
X76106Y-130290D01*
D02*
G37*
G36*
X567132Y-130806D02*
X566495D01*
X565907Y-131049D01*
X565457Y-131499D01*
X565213Y-132087D01*
Y-132724D01*
X565457Y-133312D01*
X565907Y-133762D01*
X566495Y-134005D01*
X567132D01*
X567720Y-133762D01*
X568170Y-133312D01*
X568413Y-132724D01*
Y-132087D01*
X568170Y-131499D01*
X567720Y-131049D01*
X567132Y-130806D01*
D02*
G37*
G36*
X632750Y-130880D02*
X632113D01*
X631525Y-131124D01*
X631075Y-131574D01*
X630831Y-132162D01*
Y-132799D01*
X631075Y-133387D01*
X631525Y-133837D01*
X632113Y-134080D01*
X632750D01*
X633338Y-133837D01*
X633788Y-133387D01*
X634031Y-132799D01*
Y-132162D01*
X633788Y-131574D01*
X633338Y-131124D01*
X632750Y-130880D01*
D02*
G37*
G36*
X519905Y-132996D02*
X519268D01*
X518680Y-133240D01*
X518230Y-133690D01*
X517987Y-134278D01*
Y-134914D01*
X518230Y-135502D01*
X518680Y-135952D01*
X519268Y-136196D01*
X519905D01*
X520493Y-135952D01*
X520943Y-135502D01*
X521187Y-134914D01*
Y-134278D01*
X520943Y-133690D01*
X520493Y-133240D01*
X519905Y-132996D01*
D02*
G37*
G36*
X506224Y-136047D02*
X505587D01*
X504999Y-136291D01*
X504549Y-136741D01*
X504306Y-137329D01*
Y-137966D01*
X504549Y-138554D01*
X504999Y-139004D01*
X505587Y-139247D01*
X506224D01*
X506812Y-139004D01*
X507262Y-138554D01*
X507506Y-137966D01*
Y-137329D01*
X507262Y-136741D01*
X506812Y-136291D01*
X506224Y-136047D01*
D02*
G37*
G36*
X494413D02*
X493776D01*
X493188Y-136291D01*
X492738Y-136741D01*
X492494Y-137329D01*
Y-137966D01*
X492738Y-138554D01*
X493188Y-139004D01*
X493776Y-139247D01*
X494413D01*
X495001Y-139004D01*
X495451Y-138554D01*
X495694Y-137966D01*
Y-137329D01*
X495451Y-136741D01*
X495001Y-136291D01*
X494413Y-136047D01*
D02*
G37*
G36*
X72169Y-146038D02*
X71532D01*
X70944Y-146281D01*
X70494Y-146731D01*
X70250Y-147319D01*
Y-147956D01*
X70494Y-148544D01*
X70944Y-148994D01*
X71532Y-149238D01*
X72169D01*
X72757Y-148994D01*
X73207Y-148544D01*
X73450Y-147956D01*
Y-147319D01*
X73207Y-146731D01*
X72757Y-146281D01*
X72169Y-146038D01*
D02*
G37*
G36*
X68892Y-177721D02*
X68255D01*
X67667Y-177964D01*
X67217Y-178414D01*
X66973Y-179002D01*
Y-179639D01*
X67217Y-180227D01*
X67667Y-180677D01*
X68255Y-180921D01*
X68892D01*
X69480Y-180677D01*
X69930Y-180227D01*
X70173Y-179639D01*
Y-179002D01*
X69930Y-178414D01*
X69480Y-177964D01*
X68892Y-177721D01*
D02*
G37*
G36*
X81027Y-178518D02*
X80390D01*
X79802Y-178762D01*
X79352Y-179212D01*
X79109Y-179800D01*
Y-180436D01*
X79352Y-181024D01*
X79802Y-181474D01*
X80390Y-181718D01*
X81027D01*
X81615Y-181474D01*
X82065Y-181024D01*
X82309Y-180436D01*
Y-179800D01*
X82065Y-179212D01*
X81615Y-178762D01*
X81027Y-178518D01*
D02*
G37*
G36*
X64295Y-225762D02*
X63658D01*
X63070Y-226006D01*
X62620Y-226456D01*
X62376Y-227044D01*
Y-227680D01*
X62620Y-228269D01*
X63070Y-228719D01*
X63658Y-228962D01*
X64295D01*
X64883Y-228719D01*
X65333Y-228269D01*
X65576Y-227680D01*
Y-227044D01*
X65333Y-226456D01*
X64883Y-226006D01*
X64295Y-225762D01*
D02*
G37*
G36*
X82995Y-230683D02*
X82359D01*
X81771Y-230927D01*
X81321Y-231377D01*
X81077Y-231965D01*
Y-232602D01*
X81321Y-233190D01*
X81771Y-233640D01*
X82359Y-233884D01*
X82995D01*
X83583Y-233640D01*
X84034Y-233190D01*
X84277Y-232602D01*
Y-231965D01*
X84034Y-231377D01*
X83583Y-230927D01*
X82995Y-230683D01*
D02*
G37*
G36*
X69216Y-283833D02*
X68579D01*
X67991Y-284077D01*
X67541Y-284527D01*
X67298Y-285115D01*
Y-285751D01*
X67541Y-286339D01*
X67991Y-286789D01*
X68579Y-287033D01*
X69216D01*
X69804Y-286789D01*
X70254Y-286339D01*
X70498Y-285751D01*
Y-285115D01*
X70254Y-284527D01*
X69804Y-284077D01*
X69216Y-283833D01*
D02*
G37*
G36*
X68232Y-338951D02*
X67595D01*
X67007Y-339195D01*
X66557Y-339645D01*
X66313Y-340233D01*
Y-340869D01*
X66557Y-341458D01*
X67007Y-341908D01*
X67595Y-342151D01*
X68232D01*
X68820Y-341908D01*
X69270Y-341458D01*
X69513Y-340869D01*
Y-340233D01*
X69270Y-339645D01*
X68820Y-339195D01*
X68232Y-338951D01*
D02*
G37*
G36*
X442247Y-121283D02*
X441611D01*
X441023Y-121527D01*
X440573Y-121977D01*
X440329Y-122565D01*
Y-123202D01*
X440573Y-123790D01*
X441023Y-124240D01*
X441611Y-124484D01*
X442247D01*
X442836Y-124240D01*
X443286Y-123790D01*
X443529Y-123202D01*
Y-122565D01*
X443286Y-121977D01*
X442836Y-121527D01*
X442247Y-121283D01*
D02*
G37*
G36*
X412658Y-122205D02*
X412021D01*
X411433Y-122449D01*
X410983Y-122899D01*
X410739Y-123487D01*
Y-124124D01*
X410983Y-124712D01*
X411433Y-125162D01*
X412021Y-125406D01*
X412658D01*
X413246Y-125162D01*
X413696Y-124712D01*
X413939Y-124124D01*
Y-123487D01*
X413696Y-122899D01*
X413246Y-122449D01*
X412658Y-122205D01*
D02*
G37*
G36*
X461637Y-142150D02*
X461001D01*
X460413Y-142393D01*
X459963Y-142843D01*
X459719Y-143431D01*
Y-144068D01*
X459963Y-144656D01*
X460413Y-145106D01*
X461001Y-145350D01*
X461637D01*
X462225Y-145106D01*
X462675Y-144656D01*
X462919Y-144068D01*
Y-143431D01*
X462675Y-142843D01*
X462225Y-142393D01*
X461637Y-142150D01*
D02*
G37*
G36*
X459637Y-156322D02*
X459001D01*
X458413Y-156566D01*
X457963Y-157016D01*
X457719Y-157604D01*
Y-158240D01*
X457963Y-158828D01*
X458413Y-159279D01*
X459001Y-159522D01*
X459637D01*
X460225Y-159279D01*
X460675Y-158828D01*
X460919Y-158240D01*
Y-157604D01*
X460675Y-157016D01*
X460225Y-156566D01*
X459637Y-156322D01*
D02*
G37*
G36*
Y-160910D02*
X459001D01*
X458413Y-161154D01*
X457963Y-161604D01*
X457719Y-162192D01*
Y-162829D01*
X457963Y-163417D01*
X458413Y-163867D01*
X459001Y-164110D01*
X459637D01*
X460225Y-163867D01*
X460675Y-163417D01*
X460919Y-162829D01*
Y-162192D01*
X460675Y-161604D01*
X460225Y-161154D01*
X459637Y-160910D01*
D02*
G37*
G36*
X457602Y-173547D02*
X456965D01*
X456377Y-173791D01*
X455927Y-174241D01*
X455684Y-174829D01*
Y-175466D01*
X455927Y-176054D01*
X456377Y-176504D01*
X456965Y-176747D01*
X457602D01*
X458190Y-176504D01*
X458640Y-176054D01*
X458883Y-175466D01*
Y-174829D01*
X458640Y-174241D01*
X458190Y-173791D01*
X457602Y-173547D01*
D02*
G37*
%LPD*%
D10*
X30512Y-170276D02*
X64370D01*
X64567Y-170079D01*
X63779Y-283465D02*
X64961Y-282283D01*
X26575Y-283465D02*
X63779D01*
X-23622Y-346457D02*
X67323D01*
X-23622Y-294291D02*
X66069D01*
X63189Y-241142D02*
X63324Y-241007D01*
X-23622Y-241142D02*
X63189D01*
X-23622Y-70866D02*
X31496D01*
X33465Y-68898D01*
X-23622Y-114173D02*
X31496D01*
X33465Y-116142D01*
X-23622Y-187992D02*
X67323D01*
X356578Y-225247D02*
X356641Y-225183D01*
Y-222766D01*
X352379Y-218504D02*
X356641Y-222766D01*
X123031Y-218504D02*
X352379D01*
X115157Y-226378D02*
X123031Y-218504D01*
X115157Y-315945D02*
Y-226378D01*
X101378Y-329724D02*
X115157Y-315945D01*
X87598Y-329724D02*
X101378D01*
D18*
X146457Y-114173D02*
X152362Y-120079D01*
X114173Y-114173D02*
X146457D01*
X112795Y-115551D02*
X114173Y-114173D01*
X94095Y-115551D02*
X112795D01*
X81496Y-128150D02*
X94095Y-115551D01*
X81496Y-142520D02*
Y-128150D01*
Y-142520D02*
X87317D01*
X89567Y-140270D01*
X139213Y-116929D02*
X142362Y-120079D01*
X114567Y-116929D02*
X139213D01*
X113386Y-118110D02*
X114567Y-116929D01*
X96063Y-118110D02*
X113386D01*
X83858Y-130315D02*
X96063Y-118110D01*
X83858Y-136233D02*
Y-130315D01*
Y-136233D02*
X87254Y-139629D01*
X90072Y-136811D02*
X265756D01*
X416835Y-196581D02*
X416929Y-196675D01*
Y-237008D02*
Y-196675D01*
X411811Y-235433D02*
Y-196850D01*
X366142Y-281102D02*
X411811Y-235433D01*
X316535Y-281102D02*
X366142D01*
X270472Y-327165D02*
X316535Y-281102D01*
X367717Y-286221D02*
X416929Y-237008D01*
X323228Y-286221D02*
X367717D01*
X282283Y-327165D02*
X323228Y-286221D01*
X430807Y-244390D02*
Y-175344D01*
X348031Y-327165D02*
X430807Y-244390D01*
X294094Y-327165D02*
X348031D01*
X393926Y-142520D02*
X399618Y-136828D01*
X180862Y-138111D02*
X185271Y-142520D01*
X393926D01*
X424213Y-175246D02*
Y-173425D01*
X418110Y-167323D02*
X424213Y-173425D01*
X418110Y-167323D02*
Y-153648D01*
X416796Y-152333D02*
X418110Y-153648D01*
X376349Y-152333D02*
X416796D01*
X369685Y-145669D02*
X376349Y-152333D01*
X296063Y-145669D02*
X369685D01*
X291732Y-150000D02*
X296063Y-145669D01*
X176378Y-150000D02*
X291732D01*
X169685Y-156693D02*
X176378Y-150000D01*
X142520Y-156693D02*
X169685D01*
X625000Y-48080D02*
Y-29773D01*
X248031Y-133511D02*
X411316D01*
X237008Y-129576D02*
X244097D01*
X248031Y-133511D01*
X327953Y-165354D02*
X402559D01*
X187402Y-155118D02*
X295276D01*
X312992Y-150394D02*
X327953Y-165354D01*
X300000Y-150394D02*
X312992D01*
X295276Y-155118D02*
X300000Y-150394D01*
X360236Y-162870D02*
X392434D01*
X186863Y-153818D02*
X293426D01*
X345398Y-148031D02*
X360236Y-162870D01*
X299213Y-148031D02*
X345398D01*
X293426Y-153818D02*
X299213Y-148031D01*
X179186Y-161495D02*
X186863Y-153818D01*
X179134Y-163386D02*
X187402Y-155118D01*
X403728Y-134828D02*
X405512Y-136611D01*
X395684Y-134828D02*
X403728D01*
X268631Y-132042D02*
X412800D01*
X267286Y-130697D02*
X268631Y-132042D01*
X265756Y-136811D02*
X267724Y-134843D01*
X395669D01*
X91726Y-138111D02*
X180862D01*
X89567Y-140270D02*
X91726Y-138111D01*
X87254Y-139629D02*
X90072Y-136811D01*
X412800Y-132042D02*
X437697Y-156939D01*
X395669Y-134843D02*
X395684Y-134828D01*
X411316Y-133511D02*
X433858Y-156053D01*
X65945Y-61860D02*
Y-57923D01*
X81880Y-324990D02*
Y-287582D01*
X359993Y-252984D02*
X360204D01*
X353251Y-259726D02*
X359993Y-252984D01*
X47244Y15748D02*
Y19685D01*
X40354Y16732D02*
X41339Y15748D01*
X40354Y16732D02*
Y19685D01*
X33465Y15748D02*
Y19833D01*
X26575Y16732D02*
Y19685D01*
X467520Y-163238D02*
Y-149852D01*
Y-163238D02*
X469390Y-165108D01*
X467520Y-149852D02*
X471457Y-145915D01*
X469390Y-175147D02*
Y-165108D01*
X414370Y-169291D02*
X415596Y-170518D01*
X414370Y-169291D02*
Y-157480D01*
X415596Y-178762D02*
Y-170518D01*
X415670Y-168623D02*
X419596Y-172549D01*
Y-178439D02*
Y-172549D01*
X415670Y-168623D02*
Y-156942D01*
X417596Y-178600D02*
Y-175197D01*
X358592Y-239805D02*
X363672D01*
X354452Y-235453D02*
X354852Y-235853D01*
X354452Y-235453D02*
Y-235236D01*
X354541Y-223636D02*
Y-223636D01*
X354852Y-236065D02*
Y-235853D01*
X351378Y-220472D02*
X354541Y-223636D01*
X367442Y-236035D02*
Y-216851D01*
X363672Y-239805D02*
X367442Y-236035D01*
X109519Y-203473D02*
X348548D01*
X108590Y-202173D02*
X349087D01*
X349625Y-200873D02*
X366142Y-217390D01*
X348548Y-203473D02*
X363531Y-218456D01*
X349087Y-202173D02*
X364842Y-217928D01*
X107513Y-199573D02*
X350164D01*
X364842Y-234843D02*
Y-217928D01*
X363531Y-233358D02*
Y-218456D01*
X350164Y-199573D02*
X367442Y-216851D01*
X366142Y-235382D02*
Y-217390D01*
X108052Y-200873D02*
X349625D01*
X100394Y-213366D02*
Y-210370D01*
X98425Y-215551D02*
Y-210500D01*
X97125Y-219488D02*
Y-209961D01*
X107513Y-199573D01*
X98425Y-210500D02*
X108052Y-200873D01*
X100394Y-210370D02*
X108590Y-202173D01*
X102516Y-211571D02*
Y-210476D01*
X109519Y-203473D01*
X102516Y-211571D02*
X102528Y-211583D01*
X86562Y-206411D02*
X106597Y-186376D01*
X85416Y-317699D02*
X92204Y-310911D01*
X89604Y-205207D02*
X106325Y-188487D01*
X93504Y-312439D02*
Y-206823D01*
X86562Y-211183D02*
Y-206411D01*
X89604Y-259805D02*
Y-205207D01*
X92204Y-310911D02*
Y-206284D01*
X86458Y-265779D02*
X90904Y-261334D01*
X93504Y-206823D02*
X107940Y-192387D01*
X85630Y-320313D02*
X93504Y-312439D01*
X92204Y-206284D02*
X107401Y-191087D01*
X90904Y-205746D02*
X106863Y-189787D01*
X85630Y-263779D02*
X89604Y-259805D01*
X90904Y-261334D02*
Y-205746D01*
X107940Y-192387D02*
X407486D01*
X106325Y-188487D02*
X405871D01*
X107401Y-191087D02*
X406948D01*
X106863Y-189787D02*
X406410D01*
X106597Y-186376D02*
X406143D01*
X98425Y-215551D02*
X99410Y-216535D01*
X354852Y-236065D02*
X358592Y-239805D01*
X101378Y-214567D02*
Y-214351D01*
X100394Y-213366D02*
X101378Y-214351D01*
X363019Y-238505D02*
X366142Y-235382D01*
X362480Y-237205D02*
X364842Y-234843D01*
X359692Y-238505D02*
X363019D01*
X357252Y-236065D02*
X359692Y-238505D01*
X357252Y-236065D02*
Y-235853D01*
X356852Y-235453D02*
X357252Y-235853D01*
X356852Y-235453D02*
Y-235236D01*
X84562Y-212714D02*
X85431Y-213583D01*
X84562Y-166154D02*
X89221Y-161495D01*
X84562Y-212714D02*
Y-166154D01*
X85431Y-213583D02*
X85630D01*
X360823Y-237205D02*
X362480D01*
X359652Y-236033D02*
X360823Y-237205D01*
X359252Y-235453D02*
X359652Y-235853D01*
X359252Y-235453D02*
Y-235236D01*
X359652Y-236033D02*
Y-235853D01*
X361652Y-235205D02*
X361684D01*
X363531Y-233358D01*
X85846Y-266179D02*
X86246Y-265779D01*
X85630Y-266179D02*
X85846D01*
X86246Y-265779D02*
X86458D01*
X411043Y-175058D02*
Y-174974D01*
X406143Y-186376D02*
X413286Y-179233D01*
Y-175003D01*
X407486Y-192387D02*
X421596Y-178277D01*
X103691Y-180494D02*
X405607D01*
X89567Y-166370D02*
X103691Y-180494D01*
X413286Y-175003D02*
X413440Y-174850D01*
X405607Y-180494D02*
X411043Y-175058D01*
X405871Y-188487D02*
X415596Y-178762D01*
X406410Y-189787D02*
X417596Y-178600D01*
X406948Y-191087D02*
X419596Y-178439D01*
X84646Y-278543D02*
X87598Y-275590D01*
X83180Y-303391D02*
X84646Y-301924D01*
X83180Y-323337D02*
Y-303391D01*
X84646Y-301924D02*
Y-278543D01*
X83180Y-323337D02*
X84646Y-324803D01*
X97441D01*
X111221Y-311024D01*
Y-220472D01*
X120732Y-210961D02*
X352694D01*
X361531Y-219798D01*
X111221Y-220472D02*
X120732Y-210961D01*
X351378Y-212598D02*
X359131Y-220351D01*
X112536Y-223094D02*
X123031Y-212598D01*
X351378D01*
X361531Y-223425D02*
Y-219798D01*
X81880Y-324990D02*
X83661Y-326772D01*
X100394D02*
X113189Y-313976D01*
X83661Y-326772D02*
X100394D01*
X113189Y-313976D02*
Y-224410D01*
X112536Y-223757D02*
Y-223094D01*
Y-223757D02*
X113189Y-224410D01*
X359131Y-223425D02*
Y-220351D01*
X78740Y-340551D02*
X96457D01*
X118110Y-318898D02*
Y-227362D01*
X96457Y-340551D02*
X118110Y-318898D01*
Y-227362D02*
X125000Y-220472D01*
X121063Y-263632D02*
X124969Y-259726D01*
X125000Y-220472D02*
X351378D01*
X124969Y-259726D02*
X353251D01*
X421596Y-178277D02*
Y-175034D01*
X404528Y-158595D02*
Y-156496D01*
X406812Y-154212D02*
X412940D01*
X404528Y-156496D02*
X406812Y-154212D01*
X406528Y-157767D02*
X408782Y-155512D01*
X412402D01*
X404528Y-158595D02*
X405142Y-159209D01*
X405142D01*
X406213Y-160280D02*
X407327D01*
X407480Y-160433D01*
X405142Y-159209D02*
X406213Y-160280D01*
X402559Y-165354D02*
X404528Y-163386D01*
X392434Y-162870D02*
X394794Y-160509D01*
X404604D02*
X407480Y-163386D01*
X394794Y-160509D02*
X404604D01*
X412940Y-154212D02*
X415670Y-156942D01*
X412402Y-155512D02*
X414370Y-157480D01*
X89723Y-163386D02*
X179134D01*
X89221Y-161495D02*
X179186D01*
X87567Y-165542D02*
X89723Y-163386D01*
X87167Y-166161D02*
X87567Y-165761D01*
X87167Y-166377D02*
Y-166161D01*
X87567Y-165761D02*
Y-165542D01*
X512764Y-104214D02*
X512795D01*
X505905Y-111072D02*
X512764Y-104214D01*
X463551Y-116025D02*
X485236D01*
X463520Y-116057D02*
X463551Y-116025D01*
X65945Y-61860D02*
X89173Y-85088D01*
X268898D01*
X290846Y-107037D01*
X65945Y-65797D02*
X86811Y-86663D01*
X268012D02*
X290158Y-108809D01*
X86811Y-86663D02*
X268012D01*
X290158Y-108809D02*
X434252D01*
X290846Y-107037D02*
X436024D01*
X471457Y-142470D01*
X434252Y-108809D02*
X469291Y-143848D01*
X471457Y-145915D02*
Y-142470D01*
X412339Y-123805D02*
Y-123805D01*
X275098Y-130659D02*
X416634D01*
X272835Y-128395D02*
Y-128395D01*
Y-128395D02*
X275098Y-130659D01*
X267323Y-122883D02*
X272835Y-128395D01*
X433858Y-175246D02*
Y-156053D01*
X416634Y-130659D02*
X443898Y-157923D01*
Y-175049D02*
Y-157923D01*
X437697Y-175246D02*
Y-156939D01*
X477165Y-131742D02*
X505905D01*
X475295Y-133612D02*
X477165Y-131742D01*
X505905D02*
Y-111072D01*
X485236Y-116025D02*
X487205Y-114057D01*
X458760Y-114025D02*
X483268D01*
X456742Y-116043D02*
X458760Y-114025D01*
D21*
X431637Y-327573D02*
G03*
X431930Y-326866I-707J707D01*
G01*
X432417Y-328349D02*
G03*
X433030Y-326869I-1480J1480D01*
G01*
X447244Y-324867D02*
G03*
X446416Y-326866I1999J-1999D01*
G01*
X225005Y-380873D02*
G03*
X225774Y-380554I0J1088D01*
G01*
X234076Y-353732D02*
G03*
X232127Y-358436I4704J-4704D01*
G01*
X460630Y-324852D02*
G03*
X459605Y-327326I2474J-2474D01*
G01*
X252650Y-372202D02*
G03*
X251793Y-374451I2117J-2094D01*
G01*
X431930Y-326866D02*
G03*
X431102Y-324867I-2827J0D01*
G01*
X433858Y-324867D02*
G03*
X433030Y-326866I1999J-1999D01*
G01*
X445316D02*
G03*
X444488Y-324867I-2827J0D01*
G01*
X458505Y-327326D02*
G03*
X457480Y-324852I-3499J0D01*
G01*
X465308Y-345322D02*
G03*
X465453Y-344970I-355J352D01*
G01*
X464859Y-345771D02*
G03*
X464862Y-345768I-351J356D01*
G01*
X466088Y-346098D02*
G03*
X466553Y-344970I-1135J1128D01*
G01*
X465959Y-346227D02*
G03*
X465962Y-346223I-353J355D01*
G01*
X466553Y-326098D02*
G03*
X464280Y-320992I-6872J0D01*
G01*
X450943Y-354134D02*
G03*
X462145Y-350041I1197J14098D01*
G01*
X450943Y-353034D02*
G03*
X461347Y-349283I1212J12943D01*
G01*
X465453Y-325914D02*
G03*
X463902Y-322169I-5295J-0D01*
G01*
X423940Y-332023D02*
G03*
X426257Y-326436I-5579J5587D01*
G01*
X424435Y-333084D02*
G03*
X427357Y-326029I-7055J7055D01*
G01*
X426402Y-323795D02*
G03*
X426257Y-324462I1454J-667D01*
G01*
X419657Y-334806D02*
G03*
X422217Y-333746I0J3621D01*
G01*
X427501Y-324110D02*
G03*
X427357Y-324462I355J-352D01*
G01*
X431112Y-320706D02*
G03*
X430760Y-320851I0J-500D01*
G01*
X431112Y-319606D02*
G03*
X430445Y-319752I0J-1600D01*
G01*
X212402Y-378583D02*
G03*
X212652Y-378738I4030J6227D01*
G01*
X214258Y-379178D02*
G03*
X215206Y-378455I198J723D01*
G01*
X216706Y-377977D02*
G03*
X215206Y-377977I-750J0D01*
G01*
X216706Y-379023D02*
G03*
X217456Y-379773I750J0D01*
G01*
X229198Y-375575D02*
G03*
X232127Y-368504I-7071J7071D01*
G01*
X210273Y-374722D02*
G03*
X210433Y-374655I0J227D01*
G01*
X209515Y-374722D02*
G03*
X209161Y-374868I0J-500D01*
G01*
X209161Y-374868D02*
G03*
X209015Y-375221I353J-353D01*
G01*
X209015D02*
G03*
X209161Y-375575I500J0D01*
G01*
X254893Y-337506D02*
G03*
X247054Y-340754I0J-11087D01*
G01*
X417562Y-337506D02*
G03*
X424633Y-334577I0J10000D01*
G01*
X211187Y-377601D02*
G03*
X212402Y-378583I5244J5244D01*
G01*
X229980Y-376349D02*
G03*
X233227Y-368509I-7840J7840D01*
G01*
X207915Y-375221D02*
G03*
X207768Y-374868I-500J0D01*
G01*
D02*
G03*
X207415Y-374722I-354J-354D01*
G01*
X207915Y-375449D02*
G03*
X208222Y-376192I1050J0D01*
G01*
X206496Y-374655D02*
G03*
X206656Y-374722I160J160D01*
G01*
X210420Y-378390D02*
G03*
X216416Y-380873I5996J5996D01*
G01*
X234857Y-354506D02*
G03*
X233227Y-358440I3934J-3934D01*
G01*
X254899Y-338606D02*
G03*
X247828Y-341535I0J-10000D01*
G01*
X417567Y-338606D02*
G03*
X425407Y-335359I0J11087D01*
G01*
X221108Y-376185D02*
G03*
X222638Y-374655I0J1530D01*
G01*
X440198Y-308324D02*
G03*
X439675Y-307062I-1785J0D01*
G01*
X217904Y-376102D02*
G03*
X217520Y-375984I-384J-568D01*
G01*
X215717Y-375322D02*
G03*
X217308Y-375984I1590J1576D01*
G01*
X217904Y-376102D02*
G03*
X218177Y-376185I276J417D01*
G01*
X439675Y-309586D02*
G03*
X440198Y-308324I-1262J1262D01*
G01*
X247593Y-334806D02*
G03*
X239754Y-338054I0J-11087D01*
G01*
X212957Y-371682D02*
G03*
X213579Y-373184I2124J0D01*
G01*
X436057Y-319606D02*
G03*
X436679Y-319349I0J880D01*
G01*
X439675Y-309586D02*
G03*
X439221Y-310682I1096J-1096D01*
G01*
X216204Y-361603D02*
G03*
X212957Y-369443I7840J-7840D01*
G01*
X217251Y-374601D02*
G03*
X218420Y-374116I0J1654D01*
G01*
X216056Y-374106D02*
G03*
X217251Y-374601I1194J1194D01*
G01*
X419661Y-335906D02*
G03*
X422993Y-334526I0J4712D01*
G01*
X247599Y-335906D02*
G03*
X240528Y-338835I0J-10000D01*
G01*
X216986Y-362377D02*
G03*
X214057Y-369448I7071J-7071D01*
G01*
Y-371682D02*
G03*
X214357Y-372406I1024J0D01*
G01*
X441982Y-306901D02*
G03*
X441298Y-308552I1651J-1651D01*
G01*
X440614Y-310203D02*
G03*
X441298Y-308552I-1651J1651D01*
G01*
X436062Y-320706D02*
G03*
X437453Y-320130I0J1967D01*
G01*
X440614Y-310203D02*
G03*
X440321Y-310910I707J-707D01*
G01*
X440001Y-317582D02*
G03*
X440321Y-316809I-773J773D01*
G01*
X437545Y-341806D02*
G03*
X442857Y-339606I0J7511D01*
G01*
X262949Y-341806D02*
G03*
X255109Y-345054I0J-11087D01*
G01*
X437549Y-342906D02*
G03*
X443632Y-340387I0J8602D01*
G01*
X262954Y-342906D02*
G03*
X255883Y-345835I0J-10000D01*
G01*
X249542Y-352177D02*
G03*
X246613Y-359248I7071J-7071D01*
G01*
X248762Y-351401D02*
G03*
X245513Y-359244I7842J-7842D01*
G01*
X453937Y-311649D02*
G03*
X454233Y-312359I1000J0D01*
G01*
X454329Y-312476D02*
G03*
X454256Y-312382I-428J-258D01*
G01*
X454329Y-312476D02*
G03*
X454375Y-312551I2388J1423D01*
G01*
D02*
G03*
X454751Y-313019I2342J1498D01*
G01*
X454937Y-311442D02*
G03*
X455085Y-311797I500J0D01*
G01*
X283172Y-353034D02*
G03*
X275332Y-356281I0J-11087D01*
G01*
X273719Y-357894D02*
G03*
X270914Y-364667I6773J-6773D01*
G01*
X269813Y-374162D02*
G03*
X270914Y-371505I-2657J2657D01*
G01*
X269502Y-374291D02*
G03*
X269813Y-374162I0J440D01*
G01*
X455069Y-307800D02*
G03*
X454937Y-308136I368J-339D01*
G01*
X283178Y-354134D02*
G03*
X276107Y-357063I0J-10000D01*
G01*
X274508Y-358661D02*
G03*
X272014Y-364683I6021J-6021D01*
G01*
Y-371248D02*
G03*
X273296Y-374344I4379J0D01*
G01*
X273425Y-374655D02*
G03*
X273296Y-374344I-440J0D01*
G01*
X455069Y-307800D02*
G03*
X452387Y-306744I-1132J1058D01*
G01*
X451536Y-307097D02*
G03*
X452387Y-306744I351J356D01*
G01*
X244966Y-375972D02*
G03*
X246613Y-372971I-1910J3001D01*
G01*
X238607Y-375270D02*
G03*
X244966Y-375972I3616J3608D01*
G01*
X443645Y-340373D02*
G03*
X446416Y-333684I-6690J6690D01*
G01*
X241929Y-374655D02*
G03*
X244862Y-374595I1438J1455D01*
G01*
X244994Y-374439D02*
G03*
X245061Y-374345I-2061J1552D01*
G01*
X244763Y-363361D02*
G03*
X245513Y-362611I0J750D01*
G01*
X244863Y-366361D02*
G03*
X244863Y-364861I0J750D01*
G01*
Y-369361D02*
G03*
X244863Y-367861I0J750D01*
G01*
X244561Y-363361D02*
G03*
X244561Y-364861I0J-750D01*
G01*
X244763Y-369361D02*
G03*
X244763Y-370861I0J-750D01*
G01*
X244678Y-366361D02*
G03*
X244678Y-367861I0J-750D01*
G01*
X245513Y-371611D02*
G03*
X244763Y-370861I-750J0D01*
G01*
X244862Y-374595D02*
G03*
X244992Y-374441I-1496J1395D01*
G01*
X442857Y-339606D02*
G03*
X445316Y-333669I-5938J5938D01*
G01*
X445220Y-347806D02*
G03*
X453060Y-344559I0J11087D01*
G01*
X274699Y-347806D02*
G03*
X267628Y-350735I0J-10000D01*
G01*
X259729Y-364111D02*
G03*
X259802Y-364289I251J0D01*
G01*
X262657Y-355706D02*
G03*
X259729Y-362777I7071J-7071D01*
G01*
X259655Y-367004D02*
G03*
X259653Y-367007I351J-356D01*
G01*
X456364Y-341254D02*
G03*
X459605Y-333431I-7823J7823D01*
G01*
X445215Y-346706D02*
G03*
X452286Y-343777I0J10000D01*
G01*
X274693Y-346706D02*
G03*
X266854Y-349954I0J-11087D01*
G01*
X258555Y-366297D02*
G03*
X258629Y-366120I-178J178D01*
G01*
X256382Y-374866D02*
G03*
X256890Y-374655I0J719D01*
G01*
X256258Y-374866D02*
G03*
X255841Y-375038I0J-590D01*
G01*
Y-375039D02*
G03*
X255668Y-375456I417J-417D01*
G01*
X251794Y-374454D02*
G03*
X252426Y-375861I2176J133D01*
G01*
X252429Y-375863D02*
G03*
X255508Y-375906I1562J1586D01*
G01*
X455576Y-340487D02*
G03*
X458505Y-333416I-7071J7071D01*
G01*
X259655Y-367004D02*
G03*
X259802Y-366651I-353J354D01*
G01*
X259791Y-369795D02*
G03*
X259791Y-368734I-530J530D01*
G01*
X259389Y-367271D02*
G03*
X259389Y-368332I530J-530D01*
G01*
X258131Y-369196D02*
G03*
X257070Y-369196I-530J-530D01*
G01*
X258730Y-369795D02*
G03*
X259791Y-369795I530J530D01*
G01*
X257669Y-371916D02*
G03*
X257669Y-370855I-530J530D01*
G01*
X256609Y-371916D02*
G03*
X257669Y-371916I530J530D01*
G01*
X257070Y-369196D02*
G03*
X257070Y-370256I530J-530D01*
G01*
X256207Y-371514D02*
G03*
X255146Y-371514I-530J-530D01*
G01*
X261876Y-354932D02*
G03*
X258629Y-362771I7840J-7840D01*
G01*
X255508Y-375906D02*
G03*
X255668Y-375539I-340J367D01*
G01*
X252650Y-372202D02*
X252652Y-372200D01*
X433030Y-326869D02*
Y-326866D01*
X459605Y-333431D02*
Y-327326D01*
X446416Y-333684D02*
Y-326866D01*
X445316Y-333669D02*
Y-326866D01*
X225774Y-380554D02*
X229980Y-376349D01*
X424633Y-334577D02*
X431637Y-327573D01*
X238607Y-375270D02*
X238607Y-375270D01*
X232127Y-368504D02*
Y-358436D01*
X460630Y-324852D02*
X460630Y-324852D01*
X433858Y-324867D02*
Y-324867D01*
X458505Y-333416D02*
Y-327326D01*
X447244Y-324867D02*
Y-324852D01*
X234076Y-353732D02*
X247054Y-340754D01*
X251793Y-374451D02*
X251794Y-374454D01*
X431102Y-324867D02*
Y-324852D01*
X433858Y-324867D02*
X433858Y-324867D01*
X433858Y-324867D02*
Y-324852D01*
X444488Y-324867D02*
Y-324852D01*
X466553Y-344970D02*
Y-326098D01*
X465453Y-344970D02*
Y-325914D01*
X464862Y-345768D02*
X465308Y-345322D01*
X462145Y-350041D02*
X465959Y-346227D01*
X465962Y-346223D02*
X466088Y-346098D01*
X461347Y-349283D02*
X464859Y-345771D01*
X348622Y-353034D02*
X450943D01*
X454751Y-313019D02*
X463902Y-322169D01*
X348622Y-354134D02*
X450943D01*
X426257Y-326436D02*
Y-324462D01*
X422217Y-333746D02*
X423940Y-332023D01*
X426402Y-323795D02*
X430445Y-319752D01*
X427501Y-324110D02*
X430760Y-320851D01*
X427357Y-326029D02*
Y-324462D01*
X431112Y-319606D02*
X436057D01*
X431112Y-320706D02*
X436062D01*
X212402Y-378583D02*
X212402Y-378583D01*
X212652Y-378738D02*
X214258Y-379178D01*
X214258Y-379178D02*
X214258Y-379178D01*
X215206Y-378455D02*
Y-377977D01*
X216706Y-379023D02*
Y-377977D01*
X217456Y-379773D02*
X219207D01*
X219207D01*
X219207D02*
X225000Y-379773D01*
X229198Y-375575D01*
X209515Y-374722D02*
X210273D01*
X209161Y-375575D02*
X211187Y-377601D01*
X209015Y-375221D02*
X209015D01*
X254893Y-337506D02*
X417562D01*
X207915Y-375449D02*
Y-375221D01*
X206656Y-374722D02*
X207415D01*
X216416Y-380873D02*
X225005D01*
X233227Y-368509D02*
Y-358440D01*
X234857Y-354506D02*
X247828Y-341535D01*
X254899Y-338606D02*
X417567D01*
X425407Y-335359D02*
X432417Y-328349D01*
X208222Y-376192D02*
X210420Y-378390D01*
X219285Y-376185D02*
X221108D01*
X213579Y-373184D02*
X213579Y-373184D01*
X214479Y-374084D01*
X218177Y-376185D02*
X219280D01*
X440198Y-308324D02*
X440198D01*
X217308Y-375984D02*
X217520Y-375984D01*
X214479Y-374084D02*
X215717Y-375322D01*
X219280Y-376185D02*
X219285Y-376185D01*
X439370Y-306757D02*
X439675Y-307062D01*
X247593Y-334806D02*
X419657D01*
X212957Y-371682D02*
Y-369443D01*
X436679Y-319349D02*
X439221Y-316806D01*
X436679Y-319349D02*
X436679Y-319349D01*
X439221Y-316806D02*
Y-310682D01*
X216204Y-361603D02*
X239754Y-338054D01*
X439370Y-306757D02*
Y-306742D01*
X214357Y-372406D02*
X216056Y-374106D01*
X422993Y-334526D02*
X424435Y-333084D01*
X218420Y-374116D02*
X218444Y-374109D01*
X218445Y-374108D01*
X247599Y-335906D02*
X419661D01*
X216986Y-362377D02*
X240528Y-338835D01*
X214057Y-371682D02*
Y-369448D01*
X441982Y-306901D02*
X442126Y-306757D01*
X437453Y-320130D02*
X440001Y-317582D01*
X440321Y-316809D02*
Y-310910D01*
X442126Y-306757D02*
Y-306742D01*
X262949Y-341806D02*
X437545D01*
X262954Y-342906D02*
X437549D01*
X246613Y-372967D02*
Y-359248D01*
X245513Y-360861D02*
Y-359244D01*
X249542Y-352177D02*
X255883Y-345835D01*
X248762Y-351401D02*
X255109Y-345054D01*
X283178Y-354134D02*
X348622D01*
X283172Y-353034D02*
X348622D01*
X453937Y-311649D02*
Y-306742D01*
X454937Y-311442D02*
Y-308136D01*
X454233Y-312359D02*
X454256Y-312382D01*
X455085Y-311797D02*
X464280Y-320992D01*
X270914Y-371120D02*
Y-364815D01*
X272014Y-371120D02*
Y-364815D01*
X270914Y-371505D02*
Y-371120D01*
X272014Y-371248D02*
Y-371120D01*
X270914Y-364815D02*
Y-364667D01*
X272014Y-364815D02*
Y-364683D01*
X274508Y-358661D02*
X276107Y-357063D01*
X451181Y-306742D02*
X451536Y-307097D01*
X273719Y-357894D02*
X275332Y-356281D01*
X246613Y-372971D02*
X246613Y-372967D01*
X443632Y-340387D02*
X443645Y-340373D01*
X241929Y-374655D02*
X241929Y-374655D01*
X237992D02*
X238607Y-375270D01*
X245513Y-362611D02*
Y-360861D01*
Y-372887D02*
Y-371611D01*
X245061Y-374345D02*
X245513Y-372887D01*
X244678Y-366361D02*
X244863D01*
X244763Y-369361D02*
X244863D01*
X244678Y-367861D02*
X244863D01*
X244561Y-363361D02*
X244763D01*
X244561Y-364861D02*
X244863D01*
X244992Y-374441D02*
X244994Y-374439D01*
X244763Y-370861D02*
X244763D01*
X274699Y-347806D02*
X445220D01*
X262657Y-355706D02*
X267628Y-350735D01*
X259802Y-366651D02*
Y-364289D01*
X259729Y-364111D02*
Y-362777D01*
X259565Y-367094D02*
X259653Y-367007D01*
X453060Y-344559D02*
X456364Y-341254D01*
X274693Y-346706D02*
X445215D01*
X258555Y-366297D02*
X258555Y-366297D01*
X256258Y-374866D02*
X256382D01*
X255668Y-375539D02*
Y-375456D01*
X252426Y-375861D02*
X252429Y-375863D01*
X452286Y-343777D02*
X455576Y-340487D01*
X259389Y-368332D02*
X259791Y-368734D01*
X259565Y-367094D02*
X259565Y-367094D01*
X259389Y-367271D02*
X259565Y-367094D01*
X259389Y-367271D02*
X259389Y-367271D01*
X258131Y-369196D02*
X258730Y-369795D01*
X257070Y-370256D02*
X257669Y-370855D01*
X256207Y-371514D02*
X256609Y-371916D01*
X253201Y-373459D02*
X255146Y-371514D01*
X253089Y-373994D02*
X253201Y-373459D01*
X253625Y-374431D02*
X253635Y-374421D01*
X253655D01*
X253431Y-374431D02*
X253625D01*
X253120Y-374075D02*
X253307Y-374555D01*
X253431Y-374431D01*
X253089Y-373994D02*
X253120Y-374075D01*
X261876Y-354932D02*
X266854Y-349954D01*
X258629Y-366120D02*
Y-362771D01*
X252652Y-372200D02*
X258555Y-366297D01*
D149*
X633858Y-242520D02*
X636614Y-245276D01*
X633858Y-242520D02*
Y-240945D01*
X631496Y-238583D02*
X633858Y-240945D01*
X598819Y-238583D02*
X631496D01*
X584252Y-224016D02*
X598819Y-238583D01*
X584252Y-224016D02*
Y-190945D01*
X575984Y-182677D02*
X584252Y-190945D01*
X573622Y-182677D02*
X575984D01*
X554331Y-163386D02*
X573622Y-182677D01*
X554331Y-163386D02*
Y-146899D01*
X534400Y-126969D02*
X554331Y-146899D01*
D157*
X142362Y-120079D02*
D03*
X152362D02*
D03*
X539055Y13937D02*
D03*
Y3937D02*
D03*
D158*
X172362Y-120079D02*
D03*
D159*
X282283Y-327165D02*
D03*
X294094D02*
D03*
X142520Y-156693D02*
D03*
X270472Y-327165D02*
D03*
D167*
X416835Y-196581D02*
D03*
X411811Y-196850D02*
D03*
X593307Y-127953D02*
D03*
X379134Y-137795D02*
D03*
X375984Y-120079D02*
D03*
X375532Y-123610D02*
D03*
X121063Y-263632D02*
D03*
X375590Y-127165D02*
D03*
X106299Y-263632D02*
D03*
X593307Y-131102D02*
D03*
X595276D02*
D03*
X597244D02*
D03*
X595276Y-127953D02*
D03*
X597244D02*
D03*
X640945Y-250394D02*
D03*
Y-248425D02*
D03*
Y-246457D02*
D03*
X637795Y-250394D02*
D03*
Y-248425D02*
D03*
Y-246457D02*
D03*
X625000Y-48080D02*
D03*
Y-29773D02*
D03*
X509842Y-197687D02*
D03*
Y-199655D02*
D03*
Y-201624D02*
D03*
Y-195718D02*
D03*
X447244Y-324852D02*
D03*
X433858D02*
D03*
X460630D02*
D03*
X431102D02*
D03*
X444488D02*
D03*
X457480D02*
D03*
X222638Y-374655D02*
D03*
X218445Y-374108D02*
D03*
X453937Y-306742D02*
D03*
X451181D02*
D03*
X267286Y-130697D02*
D03*
X399618Y-136828D02*
D03*
X65945Y-57923D02*
D03*
X615158Y-8858D02*
D03*
X70866Y-122047D02*
D03*
X360204Y-252984D02*
D03*
X417596Y-175197D02*
D03*
X354541Y-223636D02*
D03*
X354452Y-235236D02*
D03*
X356578Y-225247D02*
D03*
X102528Y-211583D02*
D03*
X97125Y-219488D02*
D03*
X99410Y-216535D02*
D03*
X101378Y-214567D02*
D03*
X86614Y-175197D02*
D03*
X361652Y-235205D02*
D03*
X359131Y-223425D02*
D03*
X361531D02*
D03*
X85416Y-317699D02*
D03*
X85630Y-263779D02*
D03*
X86562Y-211183D02*
D03*
X411043Y-174974D02*
D03*
X413440Y-174850D02*
D03*
X421596Y-175034D02*
D03*
X406528Y-157767D02*
D03*
X404528Y-163386D02*
D03*
X407480Y-160433D02*
D03*
X75787Y-232283D02*
D03*
X87167Y-166377D02*
D03*
X89567Y-166370D02*
D03*
X85630Y-213583D02*
D03*
Y-266179D02*
D03*
Y-320313D02*
D03*
X359252Y-235236D02*
D03*
X356852D02*
D03*
X407480Y-163386D02*
D03*
X26575Y19685D02*
D03*
X86614Y-227362D02*
D03*
X63976Y-221457D02*
D03*
Y-275590D02*
D03*
X75787Y-285433D02*
D03*
X87598Y-275590D02*
D03*
Y-281496D02*
D03*
X81880Y-287582D02*
D03*
X62992Y-329724D02*
D03*
X74803Y-339567D02*
D03*
X78740Y-340551D02*
D03*
X87598Y-335630D02*
D03*
Y-329724D02*
D03*
X63976Y-179134D02*
D03*
X74803D02*
D03*
X26575Y-283465D02*
D03*
X30512Y-170276D02*
D03*
X89567Y-140270D02*
D03*
X87254Y-139629D02*
D03*
X-23622Y-241142D02*
D03*
Y-294291D02*
D03*
Y-346457D02*
D03*
Y-70866D02*
D03*
Y-114173D02*
D03*
Y-187992D02*
D03*
X533878Y-117716D02*
D03*
X512795Y-104214D02*
D03*
X463551Y-116025D02*
D03*
X412339Y-123805D02*
D03*
X424213Y-175246D02*
D03*
X430807Y-175344D02*
D03*
X405512Y-136611D02*
D03*
X210433Y-374655D02*
D03*
X206496D02*
D03*
X442126Y-306742D02*
D03*
X439370D02*
D03*
X237992Y-374655D02*
D03*
X241929D02*
D03*
X253655Y-374421D02*
D03*
X256890Y-374655D02*
D03*
X273425D02*
D03*
X269502Y-374291D02*
D03*
X269685Y-106151D02*
D03*
X244094Y-109104D02*
D03*
X475295Y-133612D02*
D03*
X505905Y-131742D02*
D03*
X131890Y-72687D02*
D03*
X534400Y-126969D02*
D03*
X443898Y-175049D02*
D03*
X65945Y-65797D02*
D03*
X78740Y-238041D02*
D03*
X33465Y19833D02*
D03*
X40354Y19685D02*
D03*
X47244D02*
D03*
X483268Y-114025D02*
D03*
X492319Y-114970D02*
D03*
X487205Y-114057D02*
D03*
X456742Y-116043D02*
D03*
X469291Y-143848D02*
D03*
X267323Y-122883D02*
D03*
X469390Y-175147D02*
D03*
X437697Y-175246D02*
D03*
X433858D02*
D03*
X237008Y-129576D02*
D03*
D168*
X576132Y-124606D02*
D03*
M02*
